FILE_TYPE = MACRO_DRAWING;
SET COLOR_WIRE YELLOW;
SET COLOR_PROP MONO;
SET COLOR_DOT WHITE;
SET COLOR_ARC YELLOW;
SET COLOR_BODY GREEN;
SET COLOR_NOTE MONO;
SET PROP_DISPLAY VALUE;
SET PAGE_NUMBER P199;
FORCEADD ADM1278..1
(-3250 2575);
FORCEPROP 2 LASTPIN (-4000 2975) $PN 3
J 2
(-4010 2985);
DISPLAY 0.617021 (-4010 2985);
PAINT ORANGE (-4010 2985);
FORCEPROP 1 LAST LOCATION EU1D2
J 0
(-3950 3525);
DISPLAY 0.617021 (-3950 3525);
PAINT AQUA (-3950 3525);
FORCEPROP 2 LASTPIN (-4000 2425) $PN 18
J 2
(-4010 2435);
DISPLAY 0.617021 (-4010 2435);
PAINT ORANGE (-4010 2435);
FORCEPROP 2 LASTPIN (-2500 2525) $PN 23
J 0
(-2490 2535);
DISPLAY 0.617021 (-2490 2535);
PAINT ORANGE (-2490 2535);
FORCEPROP 2 LASTPIN (-4000 2025) $PN 27
J 2
(-4010 2035);
DISPLAY 0.617021 (-4010 2035);
PAINT ORANGE (-4010 2035);
FORCEPROP 2 LASTPIN (-4000 2575) $PN 7
J 2
(-4010 2585);
DISPLAY 0.617021 (-4010 2585);
PAINT ORANGE (-4010 2585);
FORCEPROP 2 LASTPIN (-2500 3125) $PN 10
J 0
(-2490 3135);
DISPLAY 0.617021 (-2490 3135);
PAINT ORANGE (-2490 3135);
FORCEPROP 2 LASTPIN (-2500 3225) $PN 14
J 0
(-2490 3235);
DISPLAY 0.617021 (-2490 3235);
PAINT ORANGE (-2490 3235);
FORCEPROP 2 LASTPIN (-2500 3275) $PN 13
J 0
(-2490 3285);
DISPLAY 0.617021 (-2490 3285);
PAINT ORANGE (-2490 3285);
FORCEPROP 2 LASTPIN (-2500 2825) $PN 20
J 0
(-2490 2835);
DISPLAY 0.617021 (-2490 2835);
PAINT ORANGE (-2490 2835);
FORCEPROP 2 LASTPIN (-2500 3025) $PN 11
J 0
(-2490 3035);
DISPLAY 0.617021 (-2490 3035);
PAINT ORANGE (-2490 3035);
FORCEPROP 2 LASTPIN (-2500 2925) $PN 19
J 0
(-2490 2935);
DISPLAY 0.617021 (-2490 2935);
PAINT ORANGE (-2490 2935);
FORCEPROP 2 LASTPIN (-2500 2625) $PN 22
J 0
(-2490 2635);
DISPLAY 0.617021 (-2490 2635);
PAINT ORANGE (-2490 2635);
FORCEPROP 2 LASTPIN (-2500 2725) $PN 24
J 0
(-2490 2735);
DISPLAY 0.617021 (-2490 2735);
PAINT ORANGE (-2490 2735);
FORCEPROP 2 LASTPIN (-2500 2425) $PN 33
J 0
(-2490 2435);
DISPLAY 0.617021 (-2490 2435);
PAINT ORANGE (-2490 2435);
FORCEPROP 1 LAST MATERIAL IC
J 0
(-3950 3475);
DISPLAY 0.617021 (-3950 3475);
PAINT SKYBLUE (-3950 3475);
FORCEPROP 2 LASTPIN (-4000 3175) $PN 2
J 2
(-4010 3185);
DISPLAY 0.617021 (-4010 3185);
PAINT ORANGE (-4010 3185);
FORCEPROP 2 LASTPIN (-4000 3125) $PN 31
J 2
(-4010 3135);
DISPLAY 0.617021 (-4010 3135);
PAINT ORANGE (-4010 3135);
FORCEPROP 2 LASTPIN (-4000 3075) $PN 32
J 2
(-4010 3085);
DISPLAY 0.617021 (-4010 3085);
PAINT ORANGE (-4010 3085);
FORCEPROP 2 LASTPIN (-4000 2925) $PN 1
J 2
(-4010 2935);
DISPLAY 0.617021 (-4010 2935);
PAINT ORANGE (-4010 2935);
FORCEPROP 2 LASTPIN (-4000 2875) $PN 4
J 2
(-4010 2885);
DISPLAY 0.617021 (-4010 2885);
PAINT ORANGE (-4010 2885);
FORCEPROP 2 LASTPIN (-4000 2775) $PN 17
J 2
(-4010 2785);
DISPLAY 0.617021 (-4010 2785);
PAINT ORANGE (-4010 2785);
FORCEPROP 2 LASTPIN (-4000 2725) $PN 16
J 2
(-4010 2735);
DISPLAY 0.617021 (-4010 2735);
PAINT ORANGE (-4010 2735);
FORCEPROP 2 LASTPIN (-4000 2675) $PN 15
J 2
(-4010 2685);
DISPLAY 0.617021 (-4010 2685);
PAINT ORANGE (-4010 2685);
FORCEPROP 2 LASTPIN (-4000 2525) $PN 8
J 2
(-4010 2535);
DISPLAY 0.617021 (-4010 2535);
PAINT ORANGE (-4010 2535);
FORCEPROP 2 LASTPIN (-4000 2375) $PN 6
J 2
(-4010 2385);
DISPLAY 0.617021 (-4010 2385);
PAINT ORANGE (-4010 2385);
FORCEPROP 2 LASTPIN (-4000 2275) $PN 9
J 2
(-4010 2285);
DISPLAY 0.617021 (-4010 2285);
PAINT ORANGE (-4010 2285);
FORCEPROP 2 LASTPIN (-4000 2225) $PN 21
J 2
(-4010 2235);
DISPLAY 0.617021 (-4010 2235);
PAINT ORANGE (-4010 2235);
FORCEPROP 2 LASTPIN (-4000 2175) $PN 25
J 2
(-4010 2185);
DISPLAY 0.617021 (-4010 2185);
PAINT ORANGE (-4010 2185);
FORCEPROP 2 LASTPIN (-4000 1875) $PN 26
J 2
(-4010 1885);
DISPLAY 0.617021 (-4010 1885);
PAINT ORANGE (-4010 1885);
FORCEPROP 2 LASTPIN (-4000 1925) $PN 29
J 2
(-4010 1935);
DISPLAY 0.617021 (-4010 1935);
PAINT ORANGE (-4010 1935);
FORCEPROP 1 LAST PART_NUMBER G99251-001
J 0
(-3950 1675);
DISPLAY 0.617021 (-3950 1675);
PAINT BLUE (-3950 1675);
FORCEPROP 2 LASTPIN (-4000 2075) $PN 28
J 2
(-4010 2085);
DISPLAY 0.617021 (-4010 2085);
PAINT ORANGE (-4010 2085);
FORCEPROP 2 LASTPIN (-4000 3275) $PN 30
J 2
(-4010 3285);
DISPLAY 0.617021 (-4010 3285);
PAINT ORANGE (-4010 3285);
FORCEPROP 2 LASTPIN (-4000 2825) $PN 5
J 2
(-4010 2835);
DISPLAY 0.617021 (-4010 2835);
PAINT ORANGE (-4010 2835);
FORCEPROP 2 LASTPIN (-4000 2325) $PN 12
J 2
(-4010 2335);
DISPLAY 0.617021 (-4010 2335);
PAINT ORANGE (-4010 2335);
FORCEPROP 1 LAST PATH I10
J 0
(-3250 3475);
PAINT GREEN (-3250 3475);
DISPLAY INVISIBLE (-3250 3475);
FORCEPROP 0 LAST ROOM HOT_SWAP
J 0
(-3950 3625);
DISPLAY 1.021277 (-3950 3625);
PAINT ORANGE (-3950 3625);
DISPLAY INVISIBLE (-3950 3625);
FORCEPROP 1 LAST PACK_TYPE SM
J 0
(-3950 3575);
PAINT SKYBLUE (-3950 3575);
DISPLAY INVISIBLE (-3950 3575);
FORCEPROP 2 LAST SEC_TYPE SM
J 0
(-3950 3575);
DISPLAY 1.021277 (-3950 3575);
PAINT ORANGE (-3950 3575);
DISPLAY INVISIBLE (-3950 3575);
FORCEPROP 2 LAST SEC 1
J 0
(-3950 3575);
DISPLAY 0.680851 (-3950 3575);
PAINT MONO (-3950 3575);
DISPLAY INVISIBLE (-3950 3575);
FORCEPROP 2 LAST CDS_LOCATION EU1D2
J 0
(-3950 3525);
DISPLAY 0.617021 (-3950 3525);
PAINT AQUA (-3950 3525);
DISPLAY INVISIBLE (-3950 3525);
FORCEPROP 2 LAST CDS_LIB mstr_controller
J 0
(-3250 2575);
PAINT ORANGE (-3250 2575);
DISPLAY INVISIBLE (-3250 2575);
FORCEADD RES..2
(-5300 800);
FORCEPROP 1 LAST PART_NUMBER G21796-133
J 0
(-5260 675);
DISPLAY 0.617021 (-5260 675);
PAINT BLUE (-5260 675);
FORCEPROP 1 LAST MATERIAL CHIP
J 0
(-5260 725);
DISPLAY 0.617021 (-5260 725);
PAINT SKYBLUE (-5260 725);
FORCEPROP 1 LASTPIN (-5300 700) $PN 2
J 0
(-5295 710);
DISPLAY 0.617021 (-5295 710);
PAINT ORANGE (-5295 710);
FORCEPROP 1 LASTPIN (-5300 900) $PN 1
J 0
(-5295 862);
DISPLAY 0.617021 (-5295 862);
PAINT ORANGE (-5295 862);
FORCEPROP 1 LAST TOLERANCE 1%
J 0
(-5255 825);
DISPLAY 0.617021 (-5255 825);
PAINT SKYBLUE (-5255 825);
FORCEPROP 1 LAST PACK_TYPE 0402
J 0
(-5260 625);
DISPLAY 0.617021 (-5260 625);
PAINT SKYBLUE (-5260 625);
FORCEPROP 1 LAST LOCATION R1D40
J 0
(-5255 925);
DISPLAY 0.617021 (-5255 925);
PAINT AQUA (-5255 925);
FORCEPROP 1 LAST VALUE 40.2K
J 0
(-5255 875);
DISPLAY 0.617021 (-5255 875);
PAINT SKYBLUE (-5255 875);
FORCEPROP 1 LAST WATTAGE 1/16W
J 0
(-5260 775);
DISPLAY 0.617021 (-5260 775);
PAINT SKYBLUE (-5260 775);
FORCEPROP 2 LAST SEC_TYPE 0402
J 0
(-5250 1025);
DISPLAY 1.021277 (-5250 1025);
PAINT ORANGE (-5250 1025);
DISPLAY INVISIBLE (-5250 1025);
FORCEPROP 2 LAST SEC 1
J 0
(-5250 1025);
DISPLAY 0.680851 (-5250 1025);
PAINT MONO (-5250 1025);
DISPLAY INVISIBLE (-5250 1025);
FORCEPROP 0 LAST ROOM HOT_SWAP
J 0
(-5250 975);
DISPLAY 1.021277 (-5250 975);
PAINT ORANGE (-5250 975);
DISPLAY INVISIBLE (-5250 975);
FORCEPROP 1 LAST PATH I100
J 0
(-5250 975);
DISPLAY 0.978723 (-5250 975);
PAINT WHITE (-5250 975);
DISPLAY INVISIBLE (-5250 975);
FORCEPROP 2 LAST CDS_LOCATION R1D40
J 0
(-5255 925);
DISPLAY 0.617021 (-5255 925);
PAINT AQUA (-5255 925);
DISPLAY INVISIBLE (-5255 925);
FORCEPROP 2 LAST CDS_LIB mstr_discrete
J 0
(-5300 800);
PAINT ORANGE (-5300 800);
DISPLAY INVISIBLE (-5300 800);
FORCEADD AGND0..1
(-5400 450);
FORCEPROP 3 LASTPIN (-5400 500) SIG_NAME AGND_HSC\g
J 0
(-5390 510);
DISPLAY 0.659574 (-5390 510);
PAINT MONO (-5390 510);
DISPLAY INVISIBLE (-5390 510);
FORCEPROP 1 LAST HDL_POWER AGND_HSC
J 1
(-5400 400);
DISPLAY 0.617021 (-5400 400);
PAINT GREEN (-5400 400);
FORCEPROP 1 LAST BODY_TYPE PLUMBING
J 0
(-5445 407);
DISPLAY 0.340426 (-5445 407);
PAINT GREEN (-5445 407);
DISPLAY INVISIBLE (-5445 407);
FORCEPROP 1 LAST VOLTAGE 0
J 0
(-5400 450);
PAINT SKYBLUE (-5400 450);
DISPLAY INVISIBLE (-5400 450);
FORCEPROP 2 LAST BOM_COST MIO_VRD_MAIN
J 0
(-5375 425);
PAINT ORANGE (-5375 425);
DISPLAY INVISIBLE (-5375 425);
FORCEPROP 2 LAST CDS_LIB mstr_symbols
J 0
(-5400 450);
PAINT MONO (-5400 450);
DISPLAY INVISIBLE (-5400 450);
FORCEPROP 1 LAST PATH I101
J 0
(-5325 450);
DISPLAY 0.872340 (-5325 450);
PAINT AQUA (-5325 450);
DISPLAY INVISIBLE (-5325 450);
FORCEPROP 2 LAST ROOM VR_P3V3
J 0
(-5425 425);
PAINT ORANGE (-5425 425);
DISPLAY INVISIBLE (-5425 425);
FORCEADD RES..2
(-5600 750);
FORCEPROP 1 LAST WATTAGE 1/16W
J 0
(-5560 725);
DISPLAY 0.617021 (-5560 725);
PAINT SKYBLUE (-5560 725);
FORCEPROP 1 LASTPIN (-5600 850) $PN 1
J 0
(-5595 812);
DISPLAY 0.617021 (-5595 812);
PAINT ORANGE (-5595 812);
FORCEPROP 1 LASTPIN (-5600 650) $PN 2
J 0
(-5595 660);
DISPLAY 0.617021 (-5595 660);
PAINT ORANGE (-5595 660);
FORCEPROP 1 LAST TOLERANCE 1.0%
J 0
(-5555 775);
DISPLAY 0.617021 (-5555 775);
PAINT SKYBLUE (-5555 775);
FORCEPROP 1 LAST MATERIAL CHIP
J 0
(-5560 675);
DISPLAY 0.617021 (-5560 675);
PAINT SKYBLUE (-5560 675);
FORCEPROP 1 LAST VALUE 16K
J 0
(-5555 825);
DISPLAY 0.617021 (-5555 825);
PAINT SKYBLUE (-5555 825);
FORCEPROP 1 LAST LOCATION R1D34
J 0
(-5555 875);
DISPLAY 0.617021 (-5555 875);
PAINT AQUA (-5555 875);
FORCEPROP 1 LAST PART_NUMBER G21796-317
J 0
(-5585 625);
DISPLAY 0.617021 (-5585 625);
PAINT BLUE (-5585 625);
FORCEPROP 1 LAST PACK_TYPE 0402
J 0
(-5560 575);
DISPLAY 0.617021 (-5560 575);
PAINT SKYBLUE (-5560 575);
FORCEPROP 2 LAST SEC 1
J 0
(-5550 975);
DISPLAY 0.680851 (-5550 975);
PAINT MONO (-5550 975);
DISPLAY INVISIBLE (-5550 975);
FORCEPROP 2 LAST SEC_TYPE 0402
J 0
(-5550 975);
DISPLAY 1.021277 (-5550 975);
PAINT ORANGE (-5550 975);
DISPLAY INVISIBLE (-5550 975);
FORCEPROP 1 LAST PATH I102
J 0
(-5550 925);
DISPLAY 0.978723 (-5550 925);
PAINT WHITE (-5550 925);
DISPLAY INVISIBLE (-5550 925);
FORCEPROP 0 LAST ROOM HOT_SWAP
J 0
(-5550 925);
DISPLAY 1.021277 (-5550 925);
PAINT ORANGE (-5550 925);
DISPLAY INVISIBLE (-5550 925);
FORCEPROP 2 LAST CDS_LOCATION R1D34
J 0
(-5555 875);
DISPLAY 0.617021 (-5555 875);
PAINT AQUA (-5555 875);
DISPLAY INVISIBLE (-5555 875);
FORCEPROP 2 LAST CDS_LIB mstr_discrete
J 0
(-5600 750);
PAINT MONO (-5600 750);
DISPLAY INVISIBLE (-5600 750);
FORCEADD CAP_A..1
R 2
(-6150 850);
FORCEPROP 1 LAST PART_NUMBER A36096-030
J 2
(-6200 700);
DISPLAY 0.617021 (-6200 700);
PAINT BLUE (-6200 700);
FORCEPROP 1 LAST VOLTAGE 16V
J 2
(-6200 850);
DISPLAY 0.617021 (-6200 850);
PAINT SKYBLUE (-6200 850);
FORCEPROP 1 LAST TOLERANCE 10%
J 2
(-6200 800);
DISPLAY 0.617021 (-6200 800);
PAINT SKYBLUE (-6200 800);
FORCEPROP 1 LAST PACK_TYPE 0402V
J 2
(-6200 650);
DISPLAY 0.617021 (-6200 650);
PAINT SKYBLUE (-6200 650);
FORCEPROP 1 LASTPIN (-6150 750) $PN 2
J 2
(-6160 730);
DISPLAY 0.787234 (-6160 730);
PAINT ORANGE (-6160 730);
FORCEPROP 1 LASTPIN (-6150 950) $PN 1
J 2
(-6160 930);
DISPLAY 0.787234 (-6160 930);
PAINT ORANGE (-6160 930);
FORCEPROP 1 LAST MATERIAL X7R
J 2
(-6200 750);
DISPLAY 0.617021 (-6200 750);
PAINT SKYBLUE (-6200 750);
FORCEPROP 1 LAST VALUE 0.1UF
J 2
(-6200 900);
DISPLAY 0.617021 (-6200 900);
PAINT SKYBLUE (-6200 900);
FORCEPROP 1 LAST LOCATION C9P15
J 2
(-6200 950);
DISPLAY 0.617021 (-6200 950);
PAINT AQUA (-6200 950);
FORCEPROP 2 LAST SEC_TYPE 0402V
J 0
(-6200 1050);
DISPLAY 1.021277 (-6200 1050);
PAINT ORANGE (-6200 1050);
DISPLAY INVISIBLE (-6200 1050);
FORCEPROP 2 LAST SEC 1
J 0
(-6200 1050);
PAINT MONO (-6200 1050);
DISPLAY INVISIBLE (-6200 1050);
FORCEPROP 1 LAST PATH I105
J 2
(-6200 1000);
DISPLAY 0.978723 (-6200 1000);
PAINT WHITE (-6200 1000);
DISPLAY INVISIBLE (-6200 1000);
FORCEPROP 0 LAST ROOM HOT_SWAP
J 0
(-6200 1000);
DISPLAY 1.021277 (-6200 1000);
PAINT ORANGE (-6200 1000);
DISPLAY INVISIBLE (-6200 1000);
FORCEPROP 2 LAST CDS_LIB dev_discrete
J 0
(-6150 850);
PAINT ORANGE (-6150 850);
DISPLAY INVISIBLE (-6150 850);
FORCEPROP 2 LAST CDS_LOCATION C9P15
J 2
(-6200 950);
DISPLAY 0.617021 (-6200 950);
PAINT AQUA (-6200 950);
DISPLAY INVISIBLE (-6200 950);
FORCEADD AGND0..1
(-6150 600);
FORCEPROP 3 LASTPIN (-6150 650) SIG_NAME AGND_HSC\g
J 0
(-6140 660);
DISPLAY 0.659574 (-6140 660);
PAINT MONO (-6140 660);
DISPLAY INVISIBLE (-6140 660);
FORCEPROP 1 LAST HDL_POWER AGND_HSC
J 1
(-6150 550);
DISPLAY 0.617021 (-6150 550);
PAINT GREEN (-6150 550);
FORCEPROP 1 LAST BODY_TYPE PLUMBING
J 0
(-6195 557);
DISPLAY 0.340426 (-6195 557);
PAINT GREEN (-6195 557);
DISPLAY INVISIBLE (-6195 557);
FORCEPROP 2 LAST BOM_COST MIO_VRD_MAIN
J 0
(-6125 575);
PAINT ORANGE (-6125 575);
DISPLAY INVISIBLE (-6125 575);
FORCEPROP 1 LAST PATH I106
J 0
(-6075 600);
DISPLAY 0.872340 (-6075 600);
PAINT AQUA (-6075 600);
DISPLAY INVISIBLE (-6075 600);
FORCEPROP 2 LAST ROOM VR_P3V3
J 0
(-6175 575);
PAINT ORANGE (-6175 575);
DISPLAY INVISIBLE (-6175 575);
FORCEPROP 2 LAST CDS_LIB mstr_symbols
J 0
(-6150 600);
PAINT MONO (-6150 600);
DISPLAY INVISIBLE (-6150 600);
FORCEPROP 1 LAST VOLTAGE 0
J 0
(-6150 600);
PAINT SKYBLUE (-6150 600);
DISPLAY INVISIBLE (-6150 600);
FORCEADD CAP_A..1
R 2
(-6075 3575);
FORCEPROP 1 LASTPIN (-6075 3475) $PN 2
J 2
(-6085 3455);
DISPLAY 0.617021 (-6085 3455);
PAINT ORANGE (-6085 3455);
FORCEPROP 1 LAST MATERIAL X7R
J 2
(-6125 3475);
DISPLAY 0.617021 (-6125 3475);
PAINT SKYBLUE (-6125 3475);
FORCEPROP 1 LAST VALUE 0.1UF
J 2
(-6125 3625);
DISPLAY 0.617021 (-6125 3625);
PAINT SKYBLUE (-6125 3625);
FORCEPROP 1 LAST VOLTAGE 16V
J 2
(-6125 3575);
DISPLAY 0.617021 (-6125 3575);
PAINT SKYBLUE (-6125 3575);
FORCEPROP 1 LAST TOLERANCE 10%
J 2
(-6125 3525);
DISPLAY 0.617021 (-6125 3525);
PAINT SKYBLUE (-6125 3525);
FORCEPROP 1 LASTPIN (-6075 3675) $PN 1
J 2
(-6085 3655);
DISPLAY 0.617021 (-6085 3655);
PAINT ORANGE (-6085 3655);
FORCEPROP 1 LAST LOCATION C1D26
J 2
(-6125 3675);
DISPLAY 0.617021 (-6125 3675);
PAINT AQUA (-6125 3675);
FORCEPROP 1 LAST PACK_TYPE 0402V
J 2
(-6125 3375);
DISPLAY 0.617021 (-6125 3375);
PAINT SKYBLUE (-6125 3375);
FORCEPROP 1 LAST PART_NUMBER A36096-030
J 2
(-6125 3425);
DISPLAY 0.617021 (-6125 3425);
PAINT BLUE (-6125 3425);
FORCEPROP 2 LAST SEC 1
J 0
(-6125 3775);
DISPLAY 0.680851 (-6125 3775);
PAINT MONO (-6125 3775);
DISPLAY INVISIBLE (-6125 3775);
FORCEPROP 2 LAST SEC_TYPE 0402V
J 0
(-6125 3775);
DISPLAY 1.021277 (-6125 3775);
PAINT ORANGE (-6125 3775);
DISPLAY INVISIBLE (-6125 3775);
FORCEPROP 2 LAST CDS_SEC 1
J 0
(-6125 3725);
PAINT ORANGE (-6125 3725);
DISPLAY INVISIBLE (-6125 3725);
FORCEPROP 1 LAST PATH I107
J 2
(-6125 3725);
DISPLAY 0.978723 (-6125 3725);
PAINT WHITE (-6125 3725);
DISPLAY INVISIBLE (-6125 3725);
FORCEPROP 0 LAST ROOM HOT_SWAP
J 0
(-6125 3725);
DISPLAY 1.021277 (-6125 3725);
PAINT ORANGE (-6125 3725);
DISPLAY INVISIBLE (-6125 3725);
FORCEPROP 2 LAST CDS_LOCATION C1D26
J 2
(-6125 3675);
DISPLAY 0.617021 (-6125 3675);
PAINT AQUA (-6125 3675);
DISPLAY INVISIBLE (-6125 3675);
FORCEPROP 2 LAST CDS_LIB dev_discrete
J 0
(-6075 3575);
PAINT ORANGE (-6075 3575);
DISPLAY INVISIBLE (-6075 3575);
FORCEADD RES..1
(-2050 925);
FORCEPROP 1 LAST VALUE 33.2
J 2
(-2075 825);
DISPLAY 0.617021 (-2075 825);
PAINT SKYBLUE (-2075 825);
FORCEPROP 1 LASTPIN (-2150 925) $PN 1
J 0
(-2138 937);
DISPLAY 0.617021 (-2138 937);
PAINT ORANGE (-2138 937);
FORCEPROP 1 LAST LOCATION R1D33
J 0
(-2100 975);
DISPLAY 0.617021 (-2100 975);
PAINT AQUA (-2100 975);
FORCEPROP 1 LAST PACK_TYPE 0402
J 0
(-1800 775);
DISPLAY 0.617021 (-1800 775);
PAINT SKYBLUE (-1800 775);
FORCEPROP 1 LASTPIN (-1950 925) $PN 2
J 0
(-1988 937);
DISPLAY 0.617021 (-1988 937);
PAINT ORANGE (-1988 937);
FORCEPROP 1 LAST TOLERANCE 1%
J 0
(-2050 825);
DISPLAY 0.617021 (-2050 825);
PAINT SKYBLUE (-2050 825);
FORCEPROP 1 LAST MATERIAL CHIP
J 0
(-2050 775);
DISPLAY 0.617021 (-2050 775);
PAINT SKYBLUE (-2050 775);
FORCEPROP 1 LAST WATTAGE 1/16W
J 2
(-2075 775);
DISPLAY 0.617021 (-2075 775);
PAINT SKYBLUE (-2075 775);
FORCEPROP 1 LAST PART_NUMBER G21796-074
J 0
(-2100 1025);
DISPLAY 0.617021 (-2100 1025);
PAINT BLUE (-2100 1025);
FORCEPROP 2 LAST SEC_TYPE 0402
J 0
(-2100 1125);
DISPLAY 1.021277 (-2100 1125);
PAINT ORANGE (-2100 1125);
DISPLAY INVISIBLE (-2100 1125);
FORCEPROP 2 LAST SEC 1
J 0
(-2100 1125);
DISPLAY 0.680851 (-2100 1125);
PAINT MONO (-2100 1125);
DISPLAY INVISIBLE (-2100 1125);
FORCEPROP 1 LAST PATH I108
J 0
(-2100 1075);
DISPLAY 0.978723 (-2100 1075);
PAINT WHITE (-2100 1075);
DISPLAY INVISIBLE (-2100 1075);
FORCEPROP 2 LAST CDS_LIB mstr_discrete
J 0
(-2050 925);
PAINT MONO (-2050 925);
DISPLAY INVISIBLE (-2050 925);
FORCEPROP 2 LAST CDS_LOCATION R1D33
J 0
(-2100 975);
DISPLAY 0.617021 (-2100 975);
PAINT AQUA (-2100 975);
DISPLAY INVISIBLE (-2100 975);
FORCEADD RES..1
(-1700 3950);
FORCEPROP 1 LAST PACK_TYPE 0402
J 0
(-1450 3800);
DISPLAY 0.617021 (-1450 3800);
PAINT SKYBLUE (-1450 3800);
FORCEPROP 1 LAST PART_NUMBER G21796-074
J 0
(-1575 3850);
DISPLAY 0.617021 (-1575 3850);
PAINT BLUE (-1575 3850);
FORCEPROP 1 LASTPIN (-1600 3950) $PN 2
J 0
(-1638 3962);
DISPLAY 0.617021 (-1638 3962);
PAINT ORANGE (-1638 3962);
FORCEPROP 1 LAST TOLERANCE 1%
J 0
(-1700 3850);
DISPLAY 0.617021 (-1700 3850);
PAINT SKYBLUE (-1700 3850);
FORCEPROP 1 LAST LOCATION R1D26
J 0
(-1750 4000);
DISPLAY 0.617021 (-1750 4000);
PAINT AQUA (-1750 4000);
FORCEPROP 1 LASTPIN (-1800 3950) $PN 1
J 0
(-1788 3962);
DISPLAY 0.617021 (-1788 3962);
PAINT ORANGE (-1788 3962);
FORCEPROP 1 LAST VALUE 33.2
J 2
(-1725 3850);
DISPLAY 0.617021 (-1725 3850);
PAINT SKYBLUE (-1725 3850);
FORCEPROP 1 LAST WATTAGE 1/16W
J 2
(-1725 3800);
DISPLAY 0.617021 (-1725 3800);
PAINT SKYBLUE (-1725 3800);
FORCEPROP 1 LAST MATERIAL CHIP
J 0
(-1700 3800);
DISPLAY 0.617021 (-1700 3800);
PAINT SKYBLUE (-1700 3800);
FORCEPROP 2 LAST SEC_TYPE 0402
J 0
(-1750 4150);
DISPLAY 1.021277 (-1750 4150);
PAINT ORANGE (-1750 4150);
DISPLAY INVISIBLE (-1750 4150);
FORCEPROP 2 LAST SEC 1
J 0
(-1750 4150);
DISPLAY 0.680851 (-1750 4150);
PAINT MONO (-1750 4150);
DISPLAY INVISIBLE (-1750 4150);
FORCEPROP 1 LAST PATH I109
J 0
(-1750 4100);
DISPLAY 0.978723 (-1750 4100);
PAINT WHITE (-1750 4100);
DISPLAY INVISIBLE (-1750 4100);
FORCEPROP 2 LAST CDS_LOCATION R1D26
J 0
(-1750 4000);
DISPLAY 0.617021 (-1750 4000);
PAINT AQUA (-1750 4000);
DISPLAY INVISIBLE (-1750 4000);
FORCEPROP 2 LAST CDS_LIB mstr_discrete
J 0
(-1700 3950);
PAINT MONO (-1700 3950);
DISPLAY INVISIBLE (-1700 3950);
FORCEADD GND..1
(-2150 2275);
FORCEPROP 3 LASTPIN (-2150 2325) SIG_NAME GND\g
J 0
(-2140 2335);
DISPLAY 0.659574 (-2140 2335);
PAINT MONO (-2140 2335);
DISPLAY INVISIBLE (-2140 2335);
FORCEPROP 1 LAST HDL_POWER GND
J 0
(-2150 2425);
DISPLAY 0.638298 (-2150 2425);
PAINT GREEN (-2150 2425);
DISPLAY INVISIBLE (-2150 2425);
FORCEPROP 1 LAST BODY_TYPE PLUMBING
J 0
(-2195 2232);
DISPLAY 0.340426 (-2195 2232);
PAINT GREEN (-2195 2232);
DISPLAY INVISIBLE (-2195 2232);
FORCEPROP 1 LAST PATH I11
J 0
(-2075 2275);
DISPLAY 0.872340 (-2075 2275);
PAINT AQUA (-2075 2275);
DISPLAY INVISIBLE (-2075 2275);
FORCEPROP 2 LAST CDS_LIB mstr_symbols
J 0
(-2150 2275);
PAINT ORANGE (-2150 2275);
DISPLAY INVISIBLE (-2150 2275);
FORCEPROP 1 LAST VOLTAGE 0
J 0
(-2150 2275);
PAINT SKYBLUE (-2150 2275);
DISPLAY INVISIBLE (-2150 2275);
FORCEPROP 1 LAST SIZE 1B
J 0
(-2075 2225);
DISPLAY 0.638298 (-2075 2225);
PAINT GREEN (-2075 2225);
DISPLAY INVISIBLE (-2075 2225);
FORCEADD RES..1
(-2050 1375);
FORCEPROP 1 LAST MATERIAL CHIP
J 0
(-2050 1225);
DISPLAY 0.617021 (-2050 1225);
PAINT SKYBLUE (-2050 1225);
FORCEPROP 1 LAST VALUE 33.2
J 2
(-2075 1275);
DISPLAY 0.617021 (-2075 1275);
PAINT SKYBLUE (-2075 1275);
FORCEPROP 1 LAST PART_NUMBER G21796-074
J 0
(-2250 1175);
DISPLAY 0.617021 (-2250 1175);
PAINT BLUE (-2250 1175);
FORCEPROP 1 LAST TOLERANCE 1%
J 0
(-2050 1275);
DISPLAY 0.617021 (-2050 1275);
PAINT SKYBLUE (-2050 1275);
FORCEPROP 1 LASTPIN (-2150 1375) $PN 1
J 0
(-2138 1387);
DISPLAY 0.617021 (-2138 1387);
PAINT ORANGE (-2138 1387);
FORCEPROP 1 LAST WATTAGE 1/16W
J 2
(-2075 1225);
DISPLAY 0.617021 (-2075 1225);
PAINT SKYBLUE (-2075 1225);
FORCEPROP 1 LAST PACK_TYPE 0402
J 0
(-1800 1225);
DISPLAY 0.617021 (-1800 1225);
PAINT SKYBLUE (-1800 1225);
FORCEPROP 1 LASTPIN (-1950 1375) $PN 2
J 0
(-1988 1387);
DISPLAY 0.617021 (-1988 1387);
PAINT ORANGE (-1988 1387);
FORCEPROP 1 LAST LOCATION R1D30
J 0
(-2100 1425);
DISPLAY 0.617021 (-2100 1425);
PAINT AQUA (-2100 1425);
FORCEPROP 2 LAST SEC 1
J 0
(-2100 1575);
DISPLAY 0.680851 (-2100 1575);
PAINT MONO (-2100 1575);
DISPLAY INVISIBLE (-2100 1575);
FORCEPROP 2 LAST SEC_TYPE 0402
J 0
(-2100 1575);
DISPLAY 1.021277 (-2100 1575);
PAINT ORANGE (-2100 1575);
DISPLAY INVISIBLE (-2100 1575);
FORCEPROP 1 LAST PATH I110
J 0
(-2100 1525);
DISPLAY 0.978723 (-2100 1525);
PAINT WHITE (-2100 1525);
DISPLAY INVISIBLE (-2100 1525);
FORCEPROP 2 LAST CDS_LOCATION R1D30
J 0
(-2100 1425);
DISPLAY 0.617021 (-2100 1425);
PAINT AQUA (-2100 1425);
DISPLAY INVISIBLE (-2100 1425);
FORCEPROP 2 LAST CDS_LIB mstr_discrete
J 0
(-2050 1375);
PAINT MONO (-2050 1375);
DISPLAY INVISIBLE (-2050 1375);
FORCEADD AGND0..1
(-6600 -25);
FORCEPROP 3 LASTPIN (-6600 25) SIG_NAME AGND_HSC\g
J 0
(-6590 35);
DISPLAY 0.659574 (-6590 35);
PAINT MONO (-6590 35);
DISPLAY INVISIBLE (-6590 35);
FORCEPROP 1 LAST HDL_POWER AGND_HSC
J 1
(-6600 -75);
DISPLAY 0.617021 (-6600 -75);
PAINT GREEN (-6600 -75);
FORCEPROP 1 LAST BODY_TYPE PLUMBING
J 0
(-6645 -68);
DISPLAY 0.340426 (-6645 -68);
PAINT GREEN (-6645 -68);
DISPLAY INVISIBLE (-6645 -68);
FORCEPROP 1 LAST VOLTAGE 0
J 0
(-6600 -25);
PAINT SKYBLUE (-6600 -25);
DISPLAY INVISIBLE (-6600 -25);
FORCEPROP 2 LAST CDS_LIB mstr_symbols
J 0
(-6600 -25);
PAINT MONO (-6600 -25);
DISPLAY INVISIBLE (-6600 -25);
FORCEPROP 1 LAST PATH I112
J 0
(-6525 -25);
DISPLAY 0.872340 (-6525 -25);
PAINT AQUA (-6525 -25);
DISPLAY INVISIBLE (-6525 -25);
FORCEPROP 2 LAST BOM_COST MIO_VRD_MAIN
J 0
(-6575 -50);
PAINT ORANGE (-6575 -50);
DISPLAY INVISIBLE (-6575 -50);
FORCEPROP 2 LAST ROOM VR_P3V3
J 0
(-6625 -50);
PAINT ORANGE (-6625 -50);
DISPLAY INVISIBLE (-6625 -50);
FORCEADD AGND0..1
(-7200 3250);
FORCEPROP 3 LASTPIN (-7200 3300) SIG_NAME AGND_HSC\g
J 0
(-7190 3310);
DISPLAY 0.659574 (-7190 3310);
PAINT MONO (-7190 3310);
DISPLAY INVISIBLE (-7190 3310);
FORCEPROP 1 LAST HDL_POWER AGND_HSC
J 1
(-7200 3200);
DISPLAY 0.617021 (-7200 3200);
PAINT GREEN (-7200 3200);
FORCEPROP 1 LAST BODY_TYPE PLUMBING
J 0
(-7245 3207);
DISPLAY 0.340426 (-7245 3207);
PAINT GREEN (-7245 3207);
DISPLAY INVISIBLE (-7245 3207);
FORCEPROP 1 LAST PATH I113
J 0
(-7125 3250);
DISPLAY 0.872340 (-7125 3250);
PAINT AQUA (-7125 3250);
DISPLAY INVISIBLE (-7125 3250);
FORCEPROP 2 LAST CDS_LIB mstr_symbols
J 0
(-7200 3250);
PAINT ORANGE (-7200 3250);
DISPLAY INVISIBLE (-7200 3250);
FORCEPROP 2 LAST ROOM VR_P3V3
J 0
(-7225 3225);
PAINT ORANGE (-7225 3225);
DISPLAY INVISIBLE (-7225 3225);
FORCEPROP 1 LAST VOLTAGE 0
J 0
(-7200 3250);
PAINT SKYBLUE (-7200 3250);
DISPLAY INVISIBLE (-7200 3250);
FORCEPROP 2 LAST BOM_COST MIO_VRD_MAIN
J 0
(-7175 3225);
PAINT ORANGE (-7175 3225);
DISPLAY INVISIBLE (-7175 3225);
FORCEADD AGND0..1
(-5525 3350);
FORCEPROP 3 LASTPIN (-5525 3400) SIG_NAME AGND_HSC\g
J 0
(-5515 3410);
DISPLAY 0.659574 (-5515 3410);
PAINT MONO (-5515 3410);
DISPLAY INVISIBLE (-5515 3410);
FORCEPROP 1 LAST HDL_POWER AGND_HSC
J 1
(-5525 3300);
DISPLAY 0.617021 (-5525 3300);
PAINT GREEN (-5525 3300);
FORCEPROP 1 LAST BODY_TYPE PLUMBING
J 0
(-5570 3307);
DISPLAY 0.340426 (-5570 3307);
PAINT GREEN (-5570 3307);
DISPLAY INVISIBLE (-5570 3307);
FORCEPROP 1 LAST PATH I115
J 0
(-5450 3350);
DISPLAY 0.872340 (-5450 3350);
PAINT AQUA (-5450 3350);
DISPLAY INVISIBLE (-5450 3350);
FORCEPROP 2 LAST CDS_LIB mstr_symbols
J 0
(-5525 3350);
PAINT ORANGE (-5525 3350);
DISPLAY INVISIBLE (-5525 3350);
FORCEPROP 1 LAST VOLTAGE 0
J 0
(-5525 3350);
PAINT SKYBLUE (-5525 3350);
DISPLAY INVISIBLE (-5525 3350);
FORCEPROP 2 LAST BOM_COST MIO_VRD_MAIN
J 0
(-5500 3325);
PAINT ORANGE (-5500 3325);
DISPLAY INVISIBLE (-5500 3325);
FORCEPROP 2 LAST ROOM VR_P3V3
J 0
(-5550 3325);
PAINT ORANGE (-5550 3325);
DISPLAY INVISIBLE (-5550 3325);
FORCEADD GND..1
(-5100 3400);
FORCEPROP 3 LASTPIN (-5100 3450) SIG_NAME GND\g
J 0
(-5090 3460);
DISPLAY 0.659574 (-5090 3460);
PAINT MONO (-5090 3460);
DISPLAY INVISIBLE (-5090 3460);
FORCEPROP 1 LAST HDL_POWER GND
J 0
(-5100 3550);
DISPLAY 0.638298 (-5100 3550);
PAINT GREEN (-5100 3550);
DISPLAY INVISIBLE (-5100 3550);
FORCEPROP 1 LAST BODY_TYPE PLUMBING
J 0
(-5145 3357);
DISPLAY 0.340426 (-5145 3357);
PAINT GREEN (-5145 3357);
DISPLAY INVISIBLE (-5145 3357);
FORCEPROP 1 LAST VOLTAGE 0
J 0
(-5100 3400);
PAINT SKYBLUE (-5100 3400);
DISPLAY INVISIBLE (-5100 3400);
FORCEPROP 1 LAST SIZE 1B
J 0
(-5025 3350);
DISPLAY 0.638298 (-5025 3350);
PAINT GREEN (-5025 3350);
DISPLAY INVISIBLE (-5025 3350);
FORCEPROP 2 LAST CDS_LIB mstr_symbols
J 0
(-5100 3400);
PAINT ORANGE (-5100 3400);
DISPLAY INVISIBLE (-5100 3400);
FORCEPROP 1 LAST PATH I116
J 0
(-5025 3400);
DISPLAY 0.872340 (-5025 3400);
PAINT AQUA (-5025 3400);
DISPLAY INVISIBLE (-5025 3400);
FORCEADD AGND0..1
(-6375 3275);
FORCEPROP 3 LASTPIN (-6375 3325) SIG_NAME AGND_HSC\g
J 0
(-6365 3335);
DISPLAY 0.659574 (-6365 3335);
PAINT MONO (-6365 3335);
DISPLAY INVISIBLE (-6365 3335);
FORCEPROP 1 LAST HDL_POWER AGND_HSC
J 1
(-6375 3225);
DISPLAY 0.617021 (-6375 3225);
PAINT GREEN (-6375 3225);
FORCEPROP 1 LAST BODY_TYPE PLUMBING
J 0
(-6420 3232);
DISPLAY 0.340426 (-6420 3232);
PAINT GREEN (-6420 3232);
DISPLAY INVISIBLE (-6420 3232);
FORCEPROP 1 LAST PATH I117
J 0
(-6300 3275);
DISPLAY 0.872340 (-6300 3275);
PAINT AQUA (-6300 3275);
DISPLAY INVISIBLE (-6300 3275);
FORCEPROP 2 LAST BOM_COST MIO_VRD_MAIN
J 0
(-6350 3250);
PAINT ORANGE (-6350 3250);
DISPLAY INVISIBLE (-6350 3250);
FORCEPROP 2 LAST CDS_LIB mstr_symbols
J 0
(-6375 3275);
PAINT ORANGE (-6375 3275);
DISPLAY INVISIBLE (-6375 3275);
FORCEPROP 1 LAST VOLTAGE 0
J 0
(-6375 3275);
PAINT SKYBLUE (-6375 3275);
DISPLAY INVISIBLE (-6375 3275);
FORCEPROP 2 LAST ROOM VR_P3V3
J 0
(-6400 3250);
PAINT ORANGE (-6400 3250);
DISPLAY INVISIBLE (-6400 3250);
FORCEADD AGND0..1
(-2375 2300);
FORCEPROP 3 LASTPIN (-2375 2350) SIG_NAME AGND_HSC\g
J 0
(-2365 2360);
DISPLAY 0.659574 (-2365 2360);
PAINT MONO (-2365 2360);
DISPLAY INVISIBLE (-2365 2360);
FORCEPROP 1 LAST HDL_POWER AGND_HSC
J 1
(-2375 2250);
DISPLAY 0.617021 (-2375 2250);
PAINT GREEN (-2375 2250);
FORCEPROP 1 LAST BODY_TYPE PLUMBING
J 0
(-2420 2257);
DISPLAY 0.340426 (-2420 2257);
PAINT GREEN (-2420 2257);
DISPLAY INVISIBLE (-2420 2257);
FORCEPROP 1 LAST PATH I118
J 0
(-2300 2300);
DISPLAY 0.872340 (-2300 2300);
PAINT AQUA (-2300 2300);
DISPLAY INVISIBLE (-2300 2300);
FORCEPROP 2 LAST ROOM VR_P3V3
J 0
(-2400 2275);
PAINT ORANGE (-2400 2275);
DISPLAY INVISIBLE (-2400 2275);
FORCEPROP 2 LAST CDS_LIB mstr_symbols
J 0
(-2375 2300);
PAINT ORANGE (-2375 2300);
DISPLAY INVISIBLE (-2375 2300);
FORCEPROP 2 LAST BOM_COST MIO_VRD_MAIN
J 0
(-2350 2275);
PAINT ORANGE (-2350 2275);
DISPLAY INVISIBLE (-2350 2275);
FORCEPROP 1 LAST VOLTAGE 0
J 0
(-2375 2300);
PAINT SKYBLUE (-2375 2300);
DISPLAY INVISIBLE (-2375 2300);
FORCEADD CAP..1
(-5650 2000);
FORCEPROP 1 LASTPIN (-5650 1900) $PN 2
J 0
(-5640 1880);
DISPLAY 0.617021 (-5640 1880);
PAINT ORANGE (-5640 1880);
FORCEPROP 1 LASTPIN (-5650 2100) $PN 1
J 0
(-5640 2080);
DISPLAY 0.617021 (-5640 2080);
PAINT ORANGE (-5640 2080);
FORCEPROP 1 LAST VOLTAGE 16V
J 0
(-5600 2000);
DISPLAY 0.617021 (-5600 2000);
PAINT SKYBLUE (-5600 2000);
FORCEPROP 1 LAST PACK_TYPE 0402
J 0
(-5425 1825);
DISPLAY 0.617021 (-5425 1825);
PAINT SKYBLUE (-5425 1825);
FORCEPROP 1 LAST TOLERANCE 10%
J 0
(-5600 1950);
DISPLAY 0.617021 (-5600 1950);
PAINT SKYBLUE (-5600 1950);
FORCEPROP 1 LAST MATERIAL X6S
J 0
(-5600 1900);
DISPLAY 0.617021 (-5600 1900);
PAINT SKYBLUE (-5600 1900);
FORCEPROP 1 LAST LOCATION C1D19
J 0
(-5600 2100);
DISPLAY 0.617021 (-5600 2100);
PAINT AQUA (-5600 2100);
FORCEPROP 1 LAST PART_NUMBER D97712-011
J 0
(-5600 1850);
DISPLAY 0.617021 (-5600 1850);
PAINT BLUE (-5600 1850);
FORCEPROP 1 LAST VALUE 1.0UF
J 0
(-5600 2050);
DISPLAY 0.617021 (-5600 2050);
PAINT SKYBLUE (-5600 2050);
FORCEPROP 2 LAST SEC_TYPE 0402
J 0
(-5600 2200);
DISPLAY 1.021277 (-5600 2200);
PAINT ORANGE (-5600 2200);
DISPLAY INVISIBLE (-5600 2200);
FORCEPROP 2 LAST SEC 1
J 0
(-5600 2200);
DISPLAY 0.680851 (-5600 2200);
PAINT MONO (-5600 2200);
DISPLAY INVISIBLE (-5600 2200);
FORCEPROP 2 LAST CDS_LOCATION C1D19
J 0
(-5600 2100);
DISPLAY 0.617021 (-5600 2100);
PAINT AQUA (-5600 2100);
DISPLAY INVISIBLE (-5600 2100);
FORCEPROP 1 LAST PATH I119
J 0
(-5600 2150);
DISPLAY 0.978723 (-5600 2150);
PAINT WHITE (-5600 2150);
DISPLAY INVISIBLE (-5600 2150);
FORCEPROP 0 LAST ROOM HOT_SWAP
J 0
(-5600 2150);
DISPLAY 1.021277 (-5600 2150);
PAINT ORANGE (-5600 2150);
DISPLAY INVISIBLE (-5600 2150);
FORCEPROP 2 LAST CDS_LIB mstr_discrete
J 0
(-5650 2000);
PAINT ORANGE (-5650 2000);
DISPLAY INVISIBLE (-5650 2000);
FORCEADD RES..2
(-6500 4050);
FORCEPROP 1 LAST PART_NUMBER G21796-010
J 0
(-6460 3925);
DISPLAY 0.617021 (-6460 3925);
PAINT BLUE (-6460 3925);
FORCEPROP 1 LAST MATERIAL CHIP
J 0
(-6460 3975);
DISPLAY 0.617021 (-6460 3975);
PAINT SKYBLUE (-6460 3975);
FORCEPROP 1 LAST WATTAGE 1/16W
J 0
(-6460 4025);
DISPLAY 0.617021 (-6460 4025);
PAINT SKYBLUE (-6460 4025);
FORCEPROP 1 LAST LOCATION R9P29
J 0
(-6455 4175);
DISPLAY 0.617021 (-6455 4175);
PAINT AQUA (-6455 4175);
FORCEPROP 1 LAST VALUE 100.0K
J 0
(-6455 4125);
DISPLAY 0.617021 (-6455 4125);
PAINT SKYBLUE (-6455 4125);
FORCEPROP 1 LAST TOLERANCE 1%
J 0
(-6455 4075);
DISPLAY 0.617021 (-6455 4075);
PAINT SKYBLUE (-6455 4075);
FORCEPROP 1 LASTPIN (-6500 4150) $PN 1
J 0
(-6495 4112);
DISPLAY 0.617021 (-6495 4112);
PAINT ORANGE (-6495 4112);
FORCEPROP 1 LASTPIN (-6500 3950) $PN 2
J 0
(-6495 3960);
DISPLAY 0.617021 (-6495 3960);
PAINT ORANGE (-6495 3960);
FORCEPROP 1 LAST PACK_TYPE 0402
J 0
(-6460 3875);
DISPLAY 0.617021 (-6460 3875);
PAINT SKYBLUE (-6460 3875);
FORCEPROP 1 LAST PATH I12
J 0
(-6450 4225);
DISPLAY 0.978723 (-6450 4225);
PAINT WHITE (-6450 4225);
DISPLAY INVISIBLE (-6450 4225);
FORCEPROP 2 LAST CDS_LIB mstr_discrete
J 0
(-6500 4050);
PAINT ORANGE (-6500 4050);
DISPLAY INVISIBLE (-6500 4050);
FORCEPROP 2 LAST SEC_TYPE 0402
J 0
(-6450 4275);
DISPLAY 1.021277 (-6450 4275);
PAINT ORANGE (-6450 4275);
DISPLAY INVISIBLE (-6450 4275);
FORCEPROP 2 LAST SEC 1
J 0
(-6450 4275);
DISPLAY 0.680851 (-6450 4275);
PAINT MONO (-6450 4275);
DISPLAY INVISIBLE (-6450 4275);
FORCEPROP 2 LAST CDS_LOCATION R9P29
J 0
(-6455 4175);
DISPLAY 0.617021 (-6455 4175);
PAINT AQUA (-6455 4175);
DISPLAY INVISIBLE (-6455 4175);
FORCEPROP 0 LAST ROOM HOT_SWAP
J 0
(-6450 4225);
DISPLAY 1.021277 (-6450 4225);
PAINT ORANGE (-6450 4225);
DISPLAY INVISIBLE (-6450 4225);
FORCEADD AGND0..1
(-5650 1800);
FORCEPROP 3 LASTPIN (-5650 1850) SIG_NAME AGND_HSC\g
J 0
(-5640 1860);
DISPLAY 0.659574 (-5640 1860);
PAINT MONO (-5640 1860);
DISPLAY INVISIBLE (-5640 1860);
FORCEPROP 1 LAST HDL_POWER AGND_HSC
J 1
(-5650 1750);
DISPLAY 0.617021 (-5650 1750);
PAINT GREEN (-5650 1750);
FORCEPROP 1 LAST BODY_TYPE PLUMBING
J 0
(-5695 1757);
DISPLAY 0.340426 (-5695 1757);
PAINT GREEN (-5695 1757);
DISPLAY INVISIBLE (-5695 1757);
FORCEPROP 1 LAST PATH I120
J 0
(-5575 1800);
DISPLAY 0.872340 (-5575 1800);
PAINT AQUA (-5575 1800);
DISPLAY INVISIBLE (-5575 1800);
FORCEPROP 2 LAST BOM_COST MIO_VRD_MAIN
J 0
(-5625 1775);
PAINT ORANGE (-5625 1775);
DISPLAY INVISIBLE (-5625 1775);
FORCEPROP 1 LAST VOLTAGE 0
J 0
(-5650 1800);
PAINT SKYBLUE (-5650 1800);
DISPLAY INVISIBLE (-5650 1800);
FORCEPROP 2 LAST CDS_LIB mstr_symbols
J 0
(-5650 1800);
PAINT ORANGE (-5650 1800);
DISPLAY INVISIBLE (-5650 1800);
FORCEPROP 2 LAST ROOM VR_P3V3
J 0
(-5675 1775);
PAINT ORANGE (-5675 1775);
DISPLAY INVISIBLE (-5675 1775);
FORCEADD CAP_A..1
R 2
(-5000 425);
FORCEPROP 1 LAST LOCATION C1D21
J 2
(-5050 525);
DISPLAY 0.617021 (-5050 525);
PAINT AQUA (-5050 525);
FORCEPROP 1 LASTPIN (-5000 525) $PN 1
J 2
(-5010 505);
DISPLAY 0.617021 (-5010 505);
PAINT ORANGE (-5010 505);
FORCEPROP 1 LASTPIN (-5000 325) $PN 2
J 2
(-5010 305);
DISPLAY 0.617021 (-5010 305);
PAINT ORANGE (-5010 305);
FORCEPROP 1 LAST VOLTAGE 16V
J 2
(-5050 425);
DISPLAY 0.617021 (-5050 425);
PAINT SKYBLUE (-5050 425);
FORCEPROP 1 LAST TOLERANCE 10%
J 2
(-5050 375);
DISPLAY 0.617021 (-5050 375);
PAINT SKYBLUE (-5050 375);
FORCEPROP 1 LAST MATERIAL X7R
J 2
(-5050 325);
DISPLAY 0.617021 (-5050 325);
PAINT SKYBLUE (-5050 325);
FORCEPROP 1 LAST PACK_TYPE 0402V
J 2
(-5050 225);
DISPLAY 0.617021 (-5050 225);
PAINT SKYBLUE (-5050 225);
FORCEPROP 1 LAST PART_NUMBER A36096-030
J 2
(-5050 275);
DISPLAY 0.617021 (-5050 275);
PAINT BLUE (-5050 275);
FORCEPROP 1 LAST VALUE 0.1UF
J 2
(-5050 475);
DISPLAY 0.617021 (-5050 475);
PAINT SKYBLUE (-5050 475);
FORCEPROP 1 LAST PATH I121
J 2
(-5050 575);
DISPLAY 0.978723 (-5050 575);
PAINT WHITE (-5050 575);
DISPLAY INVISIBLE (-5050 575);
FORCEPROP 0 LAST ROOM HOT_SWAP
J 0
(-5050 575);
DISPLAY 1.021277 (-5050 575);
PAINT ORANGE (-5050 575);
DISPLAY INVISIBLE (-5050 575);
FORCEPROP 2 LAST CDS_LOCATION C1D21
J 2
(-5050 525);
DISPLAY 0.617021 (-5050 525);
PAINT AQUA (-5050 525);
DISPLAY INVISIBLE (-5050 525);
FORCEPROP 2 LAST CDS_SEC 1
J 0
(-5050 575);
PAINT ORANGE (-5050 575);
DISPLAY INVISIBLE (-5050 575);
FORCEPROP 2 LAST SEC_TYPE 0402V
J 0
(-5050 625);
DISPLAY 1.021277 (-5050 625);
PAINT ORANGE (-5050 625);
DISPLAY INVISIBLE (-5050 625);
FORCEPROP 2 LAST SEC 1
J 0
(-5050 625);
DISPLAY 0.680851 (-5050 625);
PAINT MONO (-5050 625);
DISPLAY INVISIBLE (-5050 625);
FORCEPROP 2 LAST CDS_LIB dev_discrete
J 0
(-5000 425);
PAINT ORANGE (-5000 425);
DISPLAY INVISIBLE (-5000 425);
FORCEADD AGND0..1
(-5000 100);
FORCEPROP 3 LASTPIN (-5000 150) SIG_NAME AGND_HSC\g
J 0
(-4990 160);
DISPLAY 0.659574 (-4990 160);
PAINT MONO (-4990 160);
DISPLAY INVISIBLE (-4990 160);
FORCEPROP 1 LAST HDL_POWER AGND_HSC
J 1
(-5000 50);
DISPLAY 0.617021 (-5000 50);
PAINT GREEN (-5000 50);
FORCEPROP 1 LAST BODY_TYPE PLUMBING
J 0
(-5045 57);
DISPLAY 0.340426 (-5045 57);
PAINT GREEN (-5045 57);
DISPLAY INVISIBLE (-5045 57);
FORCEPROP 1 LAST VOLTAGE 0
J 0
(-5000 100);
PAINT SKYBLUE (-5000 100);
DISPLAY INVISIBLE (-5000 100);
FORCEPROP 2 LAST CDS_LIB mstr_symbols
J 0
(-5000 100);
PAINT ORANGE (-5000 100);
DISPLAY INVISIBLE (-5000 100);
FORCEPROP 2 LAST BOM_COST MIO_VRD_MAIN
J 0
(-4975 75);
PAINT ORANGE (-4975 75);
DISPLAY INVISIBLE (-4975 75);
FORCEPROP 1 LAST PATH I122
J 0
(-4925 100);
DISPLAY 0.872340 (-4925 100);
PAINT AQUA (-4925 100);
DISPLAY INVISIBLE (-4925 100);
FORCEPROP 2 LAST ROOM VR_P3V3
J 0
(-5025 75);
PAINT ORANGE (-5025 75);
DISPLAY INVISIBLE (-5025 75);
FORCEADD OFFPAGE..2
(-825 3275);
FORCEPROP 2 LAST $XR1 199 
J 0
(-516 3275);
DISPLAY 0.638298 (-516 3275);
PAINT MONO (-516 3275);
FORCEPROP 2 LAST $XR0 181 
J 0
(-636 3275);
DISPLAY 0.638298 (-636 3275);
PAINT MONO (-636 3275);
FORCEPROP 1 LAST COMMENT_BODY TRUE
J 0
(-870 3180);
DISPLAY 0.872340 (-870 3180);
PAINT GREEN (-870 3180);
DISPLAY INVISIBLE (-870 3180);
FORCEPROP 1 LAST OFFPAGE TRUE
J 0
(-500 3150);
DISPLAY 0.872340 (-500 3150);
PAINT GREEN (-500 3150);
DISPLAY INVISIBLE (-500 3150);
FORCEPROP 2 LAST CDS_LIB mstr_standard
J 0
(-825 3275);
PAINT ORANGE (-825 3275);
DISPLAY INVISIBLE (-825 3275);
FORCEPROP 2 LAST PATH I125
J 0
(-650 3350);
DISPLAY 1.021277 (-650 3350);
PAINT ORANGE (-650 3350);
DISPLAY INVISIBLE (-650 3350);
FORCEADD OFFPAGE..4
R 2
(-2625 3950);
FORCEPROP 2 LAST $XR1 199 
J 0
(-2997 3950);
DISPLAY 0.638298 (-2997 3950);
PAINT MONO (-2997 3950);
FORCEPROP 2 LAST $XR0 181 
J 0
(-2877 3950);
DISPLAY 0.638298 (-2877 3950);
PAINT MONO (-2877 3950);
FORCEPROP 1 LAST COMMENT_BODY TRUE
J 2
(-2600 3850);
DISPLAY 1.872340 (-2600 3850);
PAINT GREEN (-2600 3850);
DISPLAY INVISIBLE (-2600 3850);
FORCEPROP 1 LAST OFFPAGE TRUE
J 2
(-2950 3825);
PAINT GREEN (-2950 3825);
DISPLAY INVISIBLE (-2950 3825);
FORCEPROP 2 LAST CDS_LIB mstr_standard
J 0
(-2625 3950);
PAINT ORANGE (-2625 3950);
DISPLAY INVISIBLE (-2625 3950);
FORCEPROP 2 LAST PATH I126
J 0
(-2575 4025);
DISPLAY 1.021277 (-2575 4025);
PAINT ORANGE (-2575 4025);
DISPLAY INVISIBLE (-2575 4025);
FORCEADD GND..1
(-3350 -100);
FORCEPROP 3 LASTPIN (-3350 -50) SIG_NAME GND\g
J 0
(-3340 -40);
DISPLAY 0.659574 (-3340 -40);
PAINT MONO (-3340 -40);
DISPLAY INVISIBLE (-3340 -40);
FORCEPROP 1 LAST HDL_POWER GND
J 0
(-3350 50);
DISPLAY 0.638298 (-3350 50);
PAINT GREEN (-3350 50);
DISPLAY INVISIBLE (-3350 50);
FORCEPROP 1 LAST BODY_TYPE PLUMBING
J 0
(-3395 -143);
DISPLAY 0.340426 (-3395 -143);
PAINT GREEN (-3395 -143);
DISPLAY INVISIBLE (-3395 -143);
FORCEPROP 1 LAST SIZE 1B
J 0
(-3275 -150);
DISPLAY 0.638298 (-3275 -150);
PAINT GREEN (-3275 -150);
DISPLAY INVISIBLE (-3275 -150);
FORCEPROP 1 LAST VOLTAGE 0
J 0
(-3350 -100);
PAINT SKYBLUE (-3350 -100);
DISPLAY INVISIBLE (-3350 -100);
FORCEPROP 1 LAST PATH I128
J 0
(-3275 -100);
DISPLAY 0.872340 (-3275 -100);
PAINT AQUA (-3275 -100);
DISPLAY INVISIBLE (-3275 -100);
FORCEPROP 2 LAST CDS_LIB mstr_symbols
J 0
(-3350 -100);
PAINT MONO (-3350 -100);
DISPLAY INVISIBLE (-3350 -100);
FORCEADD OFFPAGE..2
(-2700 450);
FORCEPROP 2 LAST $XR0 200 
J 0
(-2511 450);
DISPLAY 0.638298 (-2511 450);
PAINT MONO (-2511 450);
FORCEPROP 1 LAST COMMENT_BODY TRUE
J 0
(-2745 355);
DISPLAY 0.872340 (-2745 355);
PAINT GREEN (-2745 355);
DISPLAY INVISIBLE (-2745 355);
FORCEPROP 1 LAST OFFPAGE TRUE
J 0
(-2375 325);
DISPLAY 0.872340 (-2375 325);
PAINT GREEN (-2375 325);
DISPLAY INVISIBLE (-2375 325);
FORCEPROP 2 LAST CDS_LIB mstr_standard
J 0
(-2700 450);
PAINT MONO (-2700 450);
DISPLAY INVISIBLE (-2700 450);
FORCEPROP 2 LAST PATH I129
J 0
(-2525 525);
DISPLAY 1.021277 (-2525 525);
PAINT ORANGE (-2525 525);
DISPLAY INVISIBLE (-2525 525);
FORCEADD RES..2
(-6500 3600);
FORCEPROP 1 LAST WATTAGE 1/16W
J 0
(-6460 3575);
DISPLAY 0.617021 (-6460 3575);
PAINT SKYBLUE (-6460 3575);
FORCEPROP 1 LAST TOLERANCE 1%
J 0
(-6455 3625);
DISPLAY 0.617021 (-6455 3625);
PAINT SKYBLUE (-6455 3625);
FORCEPROP 1 LAST PACK_TYPE 0402
J 0
(-6460 3425);
DISPLAY 0.617021 (-6460 3425);
PAINT SKYBLUE (-6460 3425);
FORCEPROP 1 LAST PART_NUMBER G21796-220
J 0
(-6460 3475);
DISPLAY 0.617021 (-6460 3475);
PAINT BLUE (-6460 3475);
FORCEPROP 1 LASTPIN (-6500 3500) $PN 2
J 0
(-6495 3510);
DISPLAY 0.617021 (-6495 3510);
PAINT ORANGE (-6495 3510);
FORCEPROP 1 LAST MATERIAL CHIP
J 0
(-6460 3525);
DISPLAY 0.617021 (-6460 3525);
PAINT SKYBLUE (-6460 3525);
FORCEPROP 1 LAST VALUE 11K
J 0
(-6455 3675);
DISPLAY 0.617021 (-6455 3675);
PAINT SKYBLUE (-6455 3675);
FORCEPROP 1 LAST LOCATION R1D42
J 0
(-6455 3725);
DISPLAY 0.617021 (-6455 3725);
PAINT AQUA (-6455 3725);
FORCEPROP 1 LASTPIN (-6500 3700) $PN 1
J 0
(-6495 3662);
DISPLAY 0.617021 (-6495 3662);
PAINT ORANGE (-6495 3662);
FORCEPROP 2 LAST SEC_TYPE 0402
J 0
(-6450 3825);
DISPLAY 1.021277 (-6450 3825);
PAINT ORANGE (-6450 3825);
DISPLAY INVISIBLE (-6450 3825);
FORCEPROP 2 LAST SEC 1
J 0
(-6450 3825);
DISPLAY 0.680851 (-6450 3825);
PAINT MONO (-6450 3825);
DISPLAY INVISIBLE (-6450 3825);
FORCEPROP 2 LAST CDS_LOCATION R1D42
J 0
(-6455 3725);
DISPLAY 0.617021 (-6455 3725);
PAINT AQUA (-6455 3725);
DISPLAY INVISIBLE (-6455 3725);
FORCEPROP 1 LAST PATH I13
J 0
(-6450 3775);
DISPLAY 0.978723 (-6450 3775);
PAINT WHITE (-6450 3775);
DISPLAY INVISIBLE (-6450 3775);
FORCEPROP 0 LAST ROOM HOT_SWAP
J 0
(-6450 3775);
DISPLAY 1.021277 (-6450 3775);
PAINT ORANGE (-6450 3775);
DISPLAY INVISIBLE (-6450 3775);
FORCEPROP 2 LAST CDS_LIB mstr_discrete
J 0
(-6500 3600);
PAINT ORANGE (-6500 3600);
DISPLAY INVISIBLE (-6500 3600);
FORCEADD FET_N..8
(-3350 200);
FORCEPROP 1 LAST PART_NUMBER C79254-001
J 0
(-3150 0);
DISPLAY 0.617021 (-3150 0);
PAINT BLUE (-3150 0);
FORCEPROP 1 LASTPIN (-3350 0) $PN 2
J 2
(-3292 0);
DISPLAY 0.617021 (-3292 0);
PAINT WHITE (-3292 0);
FORCEPROP 1 LAST MATERIAL FET
J 0
(-3150 100);
DISPLAY 0.617021 (-3150 100);
PAINT SKYBLUE (-3150 100);
FORCEPROP 1 LASTPIN (-3350 400) $PN 3
J 2
(-3297 365);
DISPLAY 0.617021 (-3297 365);
PAINT WHITE (-3297 365);
FORCEPROP 1 LASTPIN (-3550 100) $PN 1
J 2
(-3547 115);
DISPLAY 0.617021 (-3547 115);
PAINT WHITE (-3547 115);
FORCEPROP 1 LAST LOCATION Q1W5
J 0
(-3150 200);
DISPLAY 0.617021 (-3150 200);
PAINT AQUA (-3150 200);
FORCEPROP 1 LAST VALUE 2N7002
J 0
(-3150 150);
DISPLAY 0.617021 (-3150 150);
PAINT SKYBLUE (-3150 150);
FORCEPROP 1 LAST PACK_TYPE SOT23LF
J 0
(-3150 50);
DISPLAY 0.978723 (-3150 50);
PAINT SKYBLUE (-3150 50);
DISPLAY INVISIBLE (-3150 50);
FORCEPROP 0 LAST ROOM HOT_SWAP
J 0
(-3150 300);
DISPLAY 1.021277 (-3150 300);
PAINT ORANGE (-3150 300);
DISPLAY INVISIBLE (-3150 300);
FORCEPROP 2 LAST SEC_TYPE SOT23LF
J 0
(-3150 300);
DISPLAY 1.021277 (-3150 300);
PAINT ORANGE (-3150 300);
DISPLAY INVISIBLE (-3150 300);
FORCEPROP 2 LAST SEC 1
J 0
(-3150 300);
DISPLAY 0.680851 (-3150 300);
PAINT MONO (-3150 300);
DISPLAY INVISIBLE (-3150 300);
FORCEPROP 2 LAST CDS_LIB mstr_discrete
J 0
(-3350 200);
PAINT ORANGE (-3350 200);
DISPLAY INVISIBLE (-3350 200);
FORCEPROP 1 LAST PATH I130
J 0
(-3150 250);
DISPLAY 0.978723 (-3150 250);
PAINT BLUE (-3150 250);
DISPLAY INVISIBLE (-3150 250);
FORCEPROP 2 LAST CDS_LOCATION Q1W5
J 0
(-3150 200);
DISPLAY 0.617021 (-3150 200);
PAINT AQUA (-3150 200);
DISPLAY INVISIBLE (-3150 200);
FORCEADD CLX-CONN3A-1-GP..1
(-7750 725);
FORCEPROP 2 LASTPIN (-7950 800) $PN 1
J 2
(-7960 810);
DISPLAY 0.808511 (-7960 810);
PAINT ORANGE (-7960 810);
FORCEPROP 1 LAST LOCATION J1B4
J 0
(-7800 875);
DISPLAY 0.617021 (-7800 875);
PAINT GREEN (-7800 875);
FORCEPROP 2 LASTPIN (-7950 650) $PN 3
J 2
(-7960 660);
DISPLAY 0.808511 (-7960 660);
PAINT ORANGE (-7960 660);
FORCEPROP 1 LAST VALUE CLX-CONN3A-1-GP
J 0
(-7800 551);
DISPLAY 0.617021 (-7800 551);
PAINT GREEN (-7800 551);
FORCEPROP 2 LASTPIN (-7550 700) $PN 2
J 0
(-7540 710);
DISPLAY 0.808511 (-7540 710);
PAINT ORANGE (-7540 710);
FORCEPROP 1 LAST CDS_LMAN_SYM_OUTLINE -50,125,50,-125
J 0
(-7750 725);
DISPLAY 0.468085 (-7750 725);
PAINT GREEN (-7750 725);
DISPLAY INVISIBLE (-7750 725);
FORCEPROP 1 LAST PATH I131
J 0
(-7750 725);
DISPLAY 0.617021 (-7750 725);
PAINT GREEN (-7750 725);
DISPLAY INVISIBLE (-7750 725);
FORCEPROP 2 LAST CDS_LIB w_hdl
J 0
(-7750 725);
PAINT MONO (-7750 725);
DISPLAY INVISIBLE (-7750 725);
FORCEPROP 1 LAST PART_NUMBER 021.D0139.0103
J 0
(-7750 725);
DISPLAY 0.617021 (-7750 725);
PAINT GREEN (-7750 725);
DISPLAY INVISIBLE (-7750 725);
FORCEPROP 2 LAST SEC_TYPE CONN-G3
J 0
(-7800 925);
DISPLAY 1.021277 (-7800 925);
PAINT ORANGE (-7800 925);
DISPLAY INVISIBLE (-7800 925);
FORCEPROP 2 LAST SEC 1
J 0
(-7800 925);
DISPLAY 0.680851 (-7800 925);
PAINT MONO (-7800 925);
DISPLAY INVISIBLE (-7800 925);
FORCEPROP 1 LAST PACK_TYPE CONN-G3
J 0
(-7750 725);
DISPLAY 0.617021 (-7750 725);
PAINT GREEN (-7750 725);
DISPLAY INVISIBLE (-7750 725);
FORCEADD CAP..1
R 2
(-1500 1700);
FORCEPROP 1 LAST VALUE 1000PF
J 2
(-1550 1750);
DISPLAY 0.617021 (-1550 1750);
PAINT SKYBLUE (-1550 1750);
FORCEPROP 1 LAST VOLTAGE 50V
J 2
(-1550 1700);
DISPLAY 0.617021 (-1550 1700);
PAINT SKYBLUE (-1550 1700);
FORCEPROP 1 LAST PACK_TYPE 0402LF
J 2
(-1550 1500);
DISPLAY 0.617021 (-1550 1500);
PAINT SKYBLUE (-1550 1500);
FORCEPROP 1 LAST LOCATION C1W16
J 2
(-1550 1800);
DISPLAY 0.617021 (-1550 1800);
PAINT AQUA (-1550 1800);
FORCEPROP 1 LASTPIN (-1500 1800) $PN 1
J 2
(-1510 1780);
DISPLAY 0.617021 (-1510 1780);
PAINT ORANGE (-1510 1780);
FORCEPROP 1 LASTPIN (-1500 1600) $PN 2
J 2
(-1510 1580);
DISPLAY 0.617021 (-1510 1580);
PAINT ORANGE (-1510 1580);
FORCEPROP 1 LAST PART_NUMBER A36096-046
J 2
(-1550 1550);
DISPLAY 0.617021 (-1550 1550);
PAINT BLUE (-1550 1550);
FORCEPROP 1 LAST TOLERANCE 10%
J 2
(-1550 1650);
DISPLAY 0.617021 (-1550 1650);
PAINT SKYBLUE (-1550 1650);
FORCEPROP 1 LAST MATERIAL X7R
J 2
(-1550 1600);
DISPLAY 0.617021 (-1550 1600);
PAINT SKYBLUE (-1550 1600);
FORCEPROP 1 LAST PATH I132
J 2
(-1550 1850);
DISPLAY 0.978723 (-1550 1850);
PAINT WHITE (-1550 1850);
DISPLAY INVISIBLE (-1550 1850);
FORCEPROP 2 LAST CDS_LIB mstr_discrete
J 2
(-1500 1700);
PAINT ORANGE (-1500 1700);
DISPLAY INVISIBLE (-1500 1700);
FORCEPROP 2 LAST SEC_TYPE 0402LF
J 0
(-1550 1900);
DISPLAY 1.021277 (-1550 1900);
PAINT ORANGE (-1550 1900);
DISPLAY INVISIBLE (-1550 1900);
FORCEPROP 2 LAST SEC 1
J 0
(-1550 1900);
DISPLAY 0.680851 (-1550 1900);
PAINT MONO (-1550 1900);
DISPLAY INVISIBLE (-1550 1900);
FORCEPROP 2 LAST ROOM PVCCIN_CPU0_VR
J 0
(-1550 1850);
DISPLAY 1.361702 (-1550 1850);
PAINT ORANGE (-1550 1850);
DISPLAY INVISIBLE (-1550 1850);
FORCEPROP 2 LAST CDS_LOCATION C1W16
J 2
(-1550 1800);
DISPLAY 0.617021 (-1550 1800);
PAINT AQUA (-1550 1800);
DISPLAY INVISIBLE (-1550 1800);
FORCEADD GND..1
(-1500 1450);
FORCEPROP 3 LASTPIN (-1500 1500) SIG_NAME GND\g
J 0
(-1490 1510);
DISPLAY 0.659574 (-1490 1510);
PAINT MONO (-1490 1510);
DISPLAY INVISIBLE (-1490 1510);
FORCEPROP 1 LAST HDL_POWER GND
J 0
(-1500 1600);
DISPLAY 0.638298 (-1500 1600);
PAINT GREEN (-1500 1600);
DISPLAY INVISIBLE (-1500 1600);
FORCEPROP 1 LAST BODY_TYPE PLUMBING
J 0
(-1545 1407);
DISPLAY 0.340426 (-1545 1407);
PAINT GREEN (-1545 1407);
DISPLAY INVISIBLE (-1545 1407);
FORCEPROP 1 LAST PATH I133
J 0
(-1425 1450);
DISPLAY 0.872340 (-1425 1450);
PAINT AQUA (-1425 1450);
DISPLAY INVISIBLE (-1425 1450);
FORCEPROP 1 LAST VOLTAGE 0
J 0
(-1500 1450);
PAINT SKYBLUE (-1500 1450);
DISPLAY INVISIBLE (-1500 1450);
FORCEPROP 2 LAST CDS_LIB mstr_symbols
J 0
(-1500 1450);
PAINT ORANGE (-1500 1450);
DISPLAY INVISIBLE (-1500 1450);
FORCEPROP 1 LAST SIZE 1B
J 0
(-1425 1400);
DISPLAY 0.638298 (-1425 1400);
PAINT GREEN (-1425 1400);
DISPLAY INVISIBLE (-1425 1400);
FORCEADD RES..1
(-1250 1850);
FORCEPROP 1 LAST TOLERANCE 5%
J 0
(-1300 1725);
DISPLAY 0.617021 (-1300 1725);
PAINT SKYBLUE (-1300 1725);
FORCEPROP 1 LASTPIN (-1150 1850) $PN 2
J 0
(-1188 1862);
DISPLAY 0.617021 (-1188 1862);
PAINT WHITE (-1188 1862);
FORCEPROP 1 LASTPIN (-1350 1850) $PN 1
J 0
(-1338 1862);
DISPLAY 0.617021 (-1338 1862);
PAINT WHITE (-1338 1862);
FORCEPROP 1 LAST VALUE 0.0
J 2
(-1325 1725);
DISPLAY 0.617021 (-1325 1725);
PAINT SKYBLUE (-1325 1725);
FORCEPROP 1 LAST LOCATION R1W20
J 0
(-1400 1775);
DISPLAY 0.617021 (-1400 1775);
PAINT AQUA (-1400 1775);
FORCEPROP 1 LAST PACK_TYPE 0402
J 0
(-1200 1725);
DISPLAY 0.617021 (-1200 1725);
PAINT SKYBLUE (-1200 1725);
FORCEPROP 1 LAST PART_NUMBER G21497-005
J 0
(-1225 1775);
DISPLAY 0.617021 (-1225 1775);
PAINT BLUE (-1225 1775);
FORCEPROP 1 LAST WATTAGE 1/16W
J 0
(-1000 1725);
DISPLAY 0.638298 (-1000 1725);
PAINT SKYBLUE (-1000 1725);
FORCEPROP 1 LAST MATERIAL CHIP
J 0
(-975 1775);
DISPLAY 0.638298 (-975 1775);
PAINT SKYBLUE (-975 1775);
FORCEPROP 1 LAST PATH I134
J 0
(-1300 2000);
DISPLAY 0.978723 (-1300 2000);
PAINT WHITE (-1300 2000);
DISPLAY INVISIBLE (-1300 2000);
FORCEPROP 2 LAST ROOM CPU0
J 0
(-1300 2000);
PAINT PEACH (-1300 2000);
DISPLAY INVISIBLE (-1300 2000);
FORCEPROP 2 LAST SEC 1
J 0
(-1300 2075);
DISPLAY 0.680851 (-1300 2075);
PAINT MONO (-1300 2075);
DISPLAY INVISIBLE (-1300 2075);
FORCEPROP 2 LAST SEC_TYPE 0402
J 0
(-1300 2075);
DISPLAY 1.021277 (-1300 2075);
PAINT ORANGE (-1300 2075);
DISPLAY INVISIBLE (-1300 2075);
FORCEPROP 2 LAST CDS_LIB mstr_discrete
J 0
(-1250 1850);
DISPLAY 1.340426 (-1250 1850);
PAINT ORANGE (-1250 1850);
DISPLAY INVISIBLE (-1250 1850);
FORCEPROP 2 LAST BOM_COST PROC_SIDEBAND
J 0
(-1250 1850);
PAINT MONO (-1250 1850);
DISPLAY INVISIBLE (-1250 1850);
FORCEPROP 2 LAST CDS_LOCATION R1W20
J 0
(-1725 1850);
DISPLAY 0.617021 (-1725 1850);
PAINT AQUA (-1725 1850);
DISPLAY INVISIBLE (-1725 1850);
FORCEADD RES..1
(-1250 1550);
FORCEPROP 1 LAST LOCATION R1W21
J 0
(-1400 1475);
DISPLAY 0.617021 (-1400 1475);
PAINT AQUA (-1400 1475);
FORCEPROP 1 LAST VALUE 0.0
J 2
(-1325 1425);
DISPLAY 0.617021 (-1325 1425);
PAINT SKYBLUE (-1325 1425);
FORCEPROP 1 LAST TOLERANCE 5%
J 0
(-1300 1425);
DISPLAY 0.617021 (-1300 1425);
PAINT SKYBLUE (-1300 1425);
FORCEPROP 1 LAST PACK_TYPE 0402
J 0
(-1200 1425);
DISPLAY 0.617021 (-1200 1425);
PAINT SKYBLUE (-1200 1425);
FORCEPROP 1 LASTPIN (-1350 1550) $PN 1
J 0
(-1338 1562);
DISPLAY 0.617021 (-1338 1562);
PAINT WHITE (-1338 1562);
FORCEPROP 1 LASTPIN (-1150 1550) $PN 2
J 0
(-1188 1562);
DISPLAY 0.617021 (-1188 1562);
PAINT WHITE (-1188 1562);
FORCEPROP 1 LAST WATTAGE 1/16W
J 0
(-1000 1425);
DISPLAY 0.638298 (-1000 1425);
PAINT SKYBLUE (-1000 1425);
FORCEPROP 1 LAST MATERIAL CHIP
J 0
(-975 1475);
DISPLAY 0.638298 (-975 1475);
PAINT SKYBLUE (-975 1475);
FORCEPROP 1 LAST PART_NUMBER G21497-005
J 0
(-1225 1475);
DISPLAY 0.617021 (-1225 1475);
PAINT BLUE (-1225 1475);
FORCEPROP 1 LAST PATH I135
J 0
(-1300 1700);
DISPLAY 0.978723 (-1300 1700);
PAINT WHITE (-1300 1700);
DISPLAY INVISIBLE (-1300 1700);
FORCEPROP 2 LAST BOM_COST PROC_SIDEBAND
J 0
(-1250 1550);
PAINT MONO (-1250 1550);
DISPLAY INVISIBLE (-1250 1550);
FORCEPROP 2 LAST CDS_LIB mstr_discrete
J 0
(-1250 1550);
DISPLAY 1.340426 (-1250 1550);
PAINT ORANGE (-1250 1550);
DISPLAY INVISIBLE (-1250 1550);
FORCEPROP 2 LAST SEC_TYPE 0402
J 0
(-1300 1775);
DISPLAY 1.021277 (-1300 1775);
PAINT ORANGE (-1300 1775);
DISPLAY INVISIBLE (-1300 1775);
FORCEPROP 2 LAST SEC 1
J 0
(-1300 1775);
DISPLAY 0.680851 (-1300 1775);
PAINT MONO (-1300 1775);
DISPLAY INVISIBLE (-1300 1775);
FORCEPROP 2 LAST ROOM CPU0
J 0
(-1300 1700);
PAINT PEACH (-1300 1700);
DISPLAY INVISIBLE (-1300 1700);
FORCEPROP 2 LAST CDS_LOCATION R1W21
J 0
(-1725 1550);
DISPLAY 0.617021 (-1725 1550);
PAINT AQUA (-1725 1550);
DISPLAY INVISIBLE (-1725 1550);
FORCEADD RES..2
(-8000 2950);
FORCEPROP 1 LAST VALUE 4.75K
J 0
(-7955 3025);
DISPLAY 0.617021 (-7955 3025);
PAINT SKYBLUE (-7955 3025);
FORCEPROP 1 LAST LOCATION R1D29
J 0
(-7955 3075);
DISPLAY 0.617021 (-7955 3075);
PAINT AQUA (-7955 3075);
FORCEPROP 1 LASTPIN (-8000 2850) $PN 2
J 0
(-7995 2860);
DISPLAY 0.617021 (-7995 2860);
PAINT ORANGE (-7995 2860);
FORCEPROP 1 LAST MATERIAL CHIP
J 0
(-7960 2875);
DISPLAY 0.617021 (-7960 2875);
PAINT SKYBLUE (-7960 2875);
FORCEPROP 1 LAST PART_NUMBER G21796-072
J 0
(-7960 2825);
DISPLAY 0.617021 (-7960 2825);
PAINT BLUE (-7960 2825);
FORCEPROP 1 LAST PACK_TYPE 0402
J 0
(-7960 2775);
DISPLAY 0.617021 (-7960 2775);
PAINT SKYBLUE (-7960 2775);
FORCEPROP 1 LASTPIN (-8000 3050) $PN 1
J 0
(-7995 3012);
DISPLAY 0.617021 (-7995 3012);
PAINT ORANGE (-7995 3012);
FORCEPROP 1 LAST TOLERANCE 1%
J 0
(-7955 2975);
DISPLAY 0.617021 (-7955 2975);
PAINT SKYBLUE (-7955 2975);
FORCEPROP 1 LAST WATTAGE 1/16W
J 0
(-7960 2925);
DISPLAY 0.617021 (-7960 2925);
PAINT SKYBLUE (-7960 2925);
FORCEPROP 0 LAST POP NOPOP
J 0
(-7950 2725);
DISPLAY 0.638298 (-7950 2725);
PAINT RED (-7950 2725);
FORCEPROP 2 LAST CDS_LOCATION R1D29
J 0
(-7955 3075);
DISPLAY 0.617021 (-7955 3075);
PAINT AQUA (-7955 3075);
DISPLAY INVISIBLE (-7955 3075);
FORCEPROP 0 LAST CDS_SEC 1
J 0
(-7950 3125);
DISPLAY INVISIBLE (-7950 3125);
FORCEPROP 2 LAST SEC_TYPE 0402
J 0
(-7950 3175);
DISPLAY 1.021277 (-7950 3175);
PAINT ORANGE (-7950 3175);
DISPLAY INVISIBLE (-7950 3175);
FORCEPROP 2 LAST SEC 1
J 0
(-7950 3175);
DISPLAY 0.680851 (-7950 3175);
PAINT MONO (-7950 3175);
DISPLAY INVISIBLE (-7950 3175);
FORCEPROP 0 LAST ROOM CPU0
J 0
(-7950 3175);
DISPLAY 1.021277 (-7950 3175);
PAINT ORANGE (-7950 3175);
DISPLAY INVISIBLE (-7950 3175);
FORCEPROP 2 LAST CDS_LIB mstr_discrete
J 0
(-8000 2950);
PAINT ORANGE (-8000 2950);
DISPLAY INVISIBLE (-8000 2950);
FORCEPROP 1 LAST PATH I137
J 0
(-7950 3125);
DISPLAY 0.978723 (-7950 3125);
PAINT WHITE (-7950 3125);
DISPLAY INVISIBLE (-7950 3125);
FORCEADD RES..2
(-7200 4025);
FORCEPROP 1 LAST PACK_TYPE 0402
J 0
(-7160 3850);
DISPLAY 0.617021 (-7160 3850);
PAINT SKYBLUE (-7160 3850);
FORCEPROP 1 LAST MATERIAL CHIP
J 0
(-7160 3950);
DISPLAY 0.617021 (-7160 3950);
PAINT SKYBLUE (-7160 3950);
FORCEPROP 1 LAST WATTAGE 1/16W
J 0
(-7160 4000);
DISPLAY 0.617021 (-7160 4000);
PAINT SKYBLUE (-7160 4000);
FORCEPROP 1 LAST VALUE 100.0K
J 0
(-7155 4100);
DISPLAY 0.617021 (-7155 4100);
PAINT SKYBLUE (-7155 4100);
FORCEPROP 1 LAST TOLERANCE 1%
J 0
(-7155 4050);
DISPLAY 0.617021 (-7155 4050);
PAINT SKYBLUE (-7155 4050);
FORCEPROP 1 LASTPIN (-7200 4125) $PN 1
J 0
(-7195 4087);
DISPLAY 0.617021 (-7195 4087);
PAINT ORANGE (-7195 4087);
FORCEPROP 1 LASTPIN (-7200 3925) $PN 2
J 0
(-7195 3935);
DISPLAY 0.617021 (-7195 3935);
PAINT ORANGE (-7195 3935);
FORCEPROP 1 LAST LOCATION R9P28
J 0
(-7155 4150);
DISPLAY 0.617021 (-7155 4150);
PAINT AQUA (-7155 4150);
FORCEPROP 1 LAST PART_NUMBER G21796-010
J 0
(-7160 3900);
DISPLAY 0.617021 (-7160 3900);
PAINT BLUE (-7160 3900);
FORCEPROP 2 LAST CDS_LOCATION R9P28
J 0
(-7155 4150);
DISPLAY 0.617021 (-7155 4150);
PAINT AQUA (-7155 4150);
DISPLAY INVISIBLE (-7155 4150);
FORCEPROP 2 LAST CDS_LIB mstr_discrete
J 0
(-7200 4025);
PAINT ORANGE (-7200 4025);
DISPLAY INVISIBLE (-7200 4025);
FORCEPROP 2 LAST SEC_TYPE 0402
J 0
(-7150 4250);
DISPLAY 1.021277 (-7150 4250);
PAINT ORANGE (-7150 4250);
DISPLAY INVISIBLE (-7150 4250);
FORCEPROP 2 LAST SEC 1
J 0
(-7150 4250);
DISPLAY 0.680851 (-7150 4250);
PAINT MONO (-7150 4250);
DISPLAY INVISIBLE (-7150 4250);
FORCEPROP 0 LAST ROOM HOT_SWAP
J 0
(-7150 4200);
DISPLAY 1.021277 (-7150 4200);
PAINT ORANGE (-7150 4200);
DISPLAY INVISIBLE (-7150 4200);
FORCEPROP 1 LAST PATH I138
J 0
(-7150 4200);
DISPLAY 0.978723 (-7150 4200);
PAINT WHITE (-7150 4200);
DISPLAY INVISIBLE (-7150 4200);
FORCEADD RES..2
(-6600 1550);
FORCEPROP 1 LAST PART_NUMBER G21796-010
J 0
(-6560 1425);
DISPLAY 0.617021 (-6560 1425);
PAINT BLUE (-6560 1425);
FORCEPROP 1 LAST WATTAGE 1/16W
J 0
(-6560 1525);
DISPLAY 0.617021 (-6560 1525);
PAINT SKYBLUE (-6560 1525);
FORCEPROP 1 LAST TOLERANCE 1%
J 0
(-6555 1575);
DISPLAY 0.617021 (-6555 1575);
PAINT SKYBLUE (-6555 1575);
FORCEPROP 1 LAST MATERIAL CHIP
J 0
(-6560 1475);
DISPLAY 0.617021 (-6560 1475);
PAINT SKYBLUE (-6560 1475);
FORCEPROP 1 LASTPIN (-6600 1450) $PN 2
J 0
(-6595 1460);
DISPLAY 0.617021 (-6595 1460);
PAINT ORANGE (-6595 1460);
FORCEPROP 1 LAST PACK_TYPE 0402
J 0
(-6560 1375);
DISPLAY 0.617021 (-6560 1375);
PAINT SKYBLUE (-6560 1375);
FORCEPROP 1 LASTPIN (-6600 1650) $PN 1
J 0
(-6595 1612);
DISPLAY 0.617021 (-6595 1612);
PAINT ORANGE (-6595 1612);
FORCEPROP 1 LAST LOCATION R1D37
J 0
(-6555 1675);
DISPLAY 0.617021 (-6555 1675);
PAINT AQUA (-6555 1675);
FORCEPROP 1 LAST VALUE 100.0K
J 0
(-6555 1625);
DISPLAY 0.617021 (-6555 1625);
PAINT SKYBLUE (-6555 1625);
FORCEPROP 2 LAST SEC_TYPE 0402
J 0
(-6550 1775);
DISPLAY 1.021277 (-6550 1775);
PAINT ORANGE (-6550 1775);
DISPLAY INVISIBLE (-6550 1775);
FORCEPROP 2 LAST SEC 1
J 0
(-6550 1775);
DISPLAY 0.680851 (-6550 1775);
PAINT MONO (-6550 1775);
DISPLAY INVISIBLE (-6550 1775);
FORCEPROP 2 LAST CDS_LOCATION R1D37
J 0
(-6555 1675);
DISPLAY 0.617021 (-6555 1675);
PAINT AQUA (-6555 1675);
DISPLAY INVISIBLE (-6555 1675);
FORCEPROP 0 LAST NO_XNET_CONNECTION 1
J 0
(-6550 1775);
PAINT MONO (-6550 1775);
DISPLAY INVISIBLE (-6550 1775);
FORCEPROP 1 LAST PATH I15
J 0
(-6550 1725);
DISPLAY 0.978723 (-6550 1725);
PAINT WHITE (-6550 1725);
DISPLAY INVISIBLE (-6550 1725);
FORCEPROP 0 LAST ROOM HOT_SWAP
J 0
(-6550 1725);
DISPLAY 1.021277 (-6550 1725);
PAINT ORANGE (-6550 1725);
DISPLAY INVISIBLE (-6550 1725);
FORCEPROP 2 LAST CDS_LIB mstr_discrete
J 0
(-6600 1550);
PAINT ORANGE (-6600 1550);
DISPLAY INVISIBLE (-6600 1550);
FORCEADD RES..2
(-5300 1500);
FORCEPROP 1 LAST MATERIAL CHIP
J 0
(-5260 1425);
DISPLAY 0.617021 (-5260 1425);
PAINT SKYBLUE (-5260 1425);
FORCEPROP 1 LASTPIN (-5300 1400) $PN 2
J 0
(-5295 1410);
DISPLAY 0.617021 (-5295 1410);
PAINT ORANGE (-5295 1410);
FORCEPROP 1 LASTPIN (-5300 1600) $PN 1
J 0
(-5295 1562);
DISPLAY 0.617021 (-5295 1562);
PAINT ORANGE (-5295 1562);
FORCEPROP 1 LAST TOLERANCE 1%
J 0
(-5255 1525);
DISPLAY 0.617021 (-5255 1525);
PAINT SKYBLUE (-5255 1525);
FORCEPROP 1 LAST WATTAGE 1/16W
J 0
(-5260 1475);
DISPLAY 0.617021 (-5260 1475);
PAINT SKYBLUE (-5260 1475);
FORCEPROP 1 LAST VALUE 100.0K
J 0
(-5255 1575);
DISPLAY 0.617021 (-5255 1575);
PAINT SKYBLUE (-5255 1575);
FORCEPROP 1 LAST LOCATION R1D39
J 0
(-5255 1625);
DISPLAY 0.617021 (-5255 1625);
PAINT AQUA (-5255 1625);
FORCEPROP 1 LAST PACK_TYPE 0402
J 0
(-5260 1325);
DISPLAY 0.617021 (-5260 1325);
PAINT SKYBLUE (-5260 1325);
FORCEPROP 1 LAST PART_NUMBER G21796-010
J 0
(-5260 1375);
DISPLAY 0.617021 (-5260 1375);
PAINT BLUE (-5260 1375);
FORCEPROP 0 LAST ROOM HOT_SWAP
J 0
(-5250 1675);
DISPLAY 1.021277 (-5250 1675);
PAINT ORANGE (-5250 1675);
DISPLAY INVISIBLE (-5250 1675);
FORCEPROP 1 LAST PATH I16
J 0
(-5250 1675);
DISPLAY 0.978723 (-5250 1675);
PAINT WHITE (-5250 1675);
DISPLAY INVISIBLE (-5250 1675);
FORCEPROP 0 LAST NO_XNET_CONNECTION 1
J 0
(-5250 1725);
PAINT MONO (-5250 1725);
DISPLAY INVISIBLE (-5250 1725);
FORCEPROP 2 LAST CDS_LOCATION R1D39
J 0
(-5255 1625);
DISPLAY 0.617021 (-5255 1625);
PAINT AQUA (-5255 1625);
DISPLAY INVISIBLE (-5255 1625);
FORCEPROP 2 LAST SEC 1
J 0
(-5250 1725);
DISPLAY 0.680851 (-5250 1725);
PAINT MONO (-5250 1725);
DISPLAY INVISIBLE (-5250 1725);
FORCEPROP 2 LAST SEC_TYPE 0402
J 0
(-5250 1725);
DISPLAY 1.021277 (-5250 1725);
PAINT ORANGE (-5250 1725);
DISPLAY INVISIBLE (-5250 1725);
FORCEPROP 2 LAST CDS_LIB mstr_discrete
J 0
(-5300 1500);
PAINT ORANGE (-5300 1500);
DISPLAY INVISIBLE (-5300 1500);
FORCEADD RES..2
(-5600 1500);
FORCEPROP 1 LAST MATERIAL CHIP
J 0
(-5560 1425);
DISPLAY 0.617021 (-5560 1425);
PAINT SKYBLUE (-5560 1425);
FORCEPROP 1 LAST PART_NUMBER G21796-010
J 0
(-5560 1375);
DISPLAY 0.617021 (-5560 1375);
PAINT BLUE (-5560 1375);
FORCEPROP 1 LAST LOCATION R1D32
J 0
(-5555 1625);
DISPLAY 0.617021 (-5555 1625);
PAINT AQUA (-5555 1625);
FORCEPROP 1 LAST PACK_TYPE 0402
J 0
(-5560 1325);
DISPLAY 0.617021 (-5560 1325);
PAINT SKYBLUE (-5560 1325);
FORCEPROP 1 LASTPIN (-5600 1600) $PN 1
J 0
(-5595 1562);
DISPLAY 0.617021 (-5595 1562);
PAINT ORANGE (-5595 1562);
FORCEPROP 1 LAST VALUE 100.0K
J 0
(-5555 1575);
DISPLAY 0.617021 (-5555 1575);
PAINT SKYBLUE (-5555 1575);
FORCEPROP 1 LASTPIN (-5600 1400) $PN 2
J 0
(-5595 1410);
DISPLAY 0.617021 (-5595 1410);
PAINT ORANGE (-5595 1410);
FORCEPROP 1 LAST TOLERANCE 1%
J 0
(-5555 1525);
DISPLAY 0.617021 (-5555 1525);
PAINT SKYBLUE (-5555 1525);
FORCEPROP 1 LAST WATTAGE 1/16W
J 0
(-5560 1475);
DISPLAY 0.617021 (-5560 1475);
PAINT SKYBLUE (-5560 1475);
FORCEPROP 2 LAST SEC_TYPE 0402
J 0
(-5550 1725);
DISPLAY 1.021277 (-5550 1725);
PAINT ORANGE (-5550 1725);
DISPLAY INVISIBLE (-5550 1725);
FORCEPROP 2 LAST SEC 1
J 0
(-5550 1725);
DISPLAY 0.680851 (-5550 1725);
PAINT MONO (-5550 1725);
DISPLAY INVISIBLE (-5550 1725);
FORCEPROP 0 LAST NO_XNET_CONNECTION 1
J 0
(-5550 1725);
PAINT MONO (-5550 1725);
DISPLAY INVISIBLE (-5550 1725);
FORCEPROP 1 LAST PATH I17
J 0
(-5550 1675);
DISPLAY 0.978723 (-5550 1675);
PAINT WHITE (-5550 1675);
DISPLAY INVISIBLE (-5550 1675);
FORCEPROP 0 LAST ROOM HOT_SWAP
J 0
(-5550 1675);
DISPLAY 1.021277 (-5550 1675);
PAINT ORANGE (-5550 1675);
DISPLAY INVISIBLE (-5550 1675);
FORCEPROP 2 LAST CDS_LOCATION R1D32
J 0
(-5555 1625);
DISPLAY 0.617021 (-5555 1625);
PAINT AQUA (-5555 1625);
DISPLAY INVISIBLE (-5555 1625);
FORCEPROP 2 LAST CDS_LIB mstr_discrete
J 0
(-5600 1500);
PAINT ORANGE (-5600 1500);
DISPLAY INVISIBLE (-5600 1500);
FORCEADD AGND0..1
(-1350 150);
FORCEPROP 3 LASTPIN (-1350 200) SIG_NAME AGND_HSC\g
J 0
(-1340 210);
DISPLAY 0.659574 (-1340 210);
PAINT MONO (-1340 210);
DISPLAY INVISIBLE (-1340 210);
FORCEPROP 1 LAST HDL_POWER AGND_HSC
J 1
(-1350 100);
DISPLAY 0.617021 (-1350 100);
PAINT GREEN (-1350 100);
FORCEPROP 1 LAST BODY_TYPE PLUMBING
J 0
(-1395 107);
DISPLAY 0.340426 (-1395 107);
PAINT GREEN (-1395 107);
DISPLAY INVISIBLE (-1395 107);
FORCEPROP 1 LAST VOLTAGE 0
J 0
(-1350 150);
PAINT SKYBLUE (-1350 150);
DISPLAY INVISIBLE (-1350 150);
FORCEPROP 2 LAST CDS_LIB mstr_symbols
J 0
(-1350 150);
PAINT ORANGE (-1350 150);
DISPLAY INVISIBLE (-1350 150);
FORCEPROP 2 LAST BOM_COST MIO_VRD_MAIN
J 0
(-1325 125);
PAINT ORANGE (-1325 125);
DISPLAY INVISIBLE (-1325 125);
FORCEPROP 1 LAST PATH I18
J 0
(-1275 150);
DISPLAY 0.872340 (-1275 150);
PAINT AQUA (-1275 150);
DISPLAY INVISIBLE (-1275 150);
FORCEPROP 2 LAST ROOM VR_P3V3
J 0
(-1375 125);
PAINT ORANGE (-1375 125);
DISPLAY INVISIBLE (-1375 125);
FORCEADD RES..1
(-1650 300);
FORCEPROP 1 LASTPIN (-1550 300) $PN 2
J 0
(-1588 312);
DISPLAY 0.617021 (-1588 312);
PAINT ORANGE (-1588 312);
FORCEPROP 1 LAST LOCATION R1D41
J 0
(-1700 350);
DISPLAY 0.617021 (-1700 350);
PAINT AQUA (-1700 350);
FORCEPROP 1 LAST PART_NUMBER G22179-004
J 0
(-1700 400);
DISPLAY 0.617021 (-1700 400);
PAINT BLUE (-1700 400);
FORCEPROP 1 LASTPIN (-1750 300) $PN 1
J 0
(-1738 312);
DISPLAY 0.617021 (-1738 312);
PAINT ORANGE (-1738 312);
FORCEPROP 1 LAST MATERIAL CHIP
J 0
(-1650 150);
DISPLAY 0.617021 (-1650 150);
PAINT SKYBLUE (-1650 150);
FORCEPROP 1 LAST TOLERANCE 5%
J 0
(-1650 200);
DISPLAY 0.617021 (-1650 200);
PAINT SKYBLUE (-1650 200);
FORCEPROP 1 LAST PACK_TYPE 0805
J 0
(-1725 100);
DISPLAY 0.617021 (-1725 100);
PAINT SKYBLUE (-1725 100);
FORCEPROP 1 LAST WATTAGE 1/8W
J 2
(-1675 150);
DISPLAY 0.617021 (-1675 150);
PAINT SKYBLUE (-1675 150);
FORCEPROP 1 LAST VALUE 0.0
J 2
(-1675 200);
DISPLAY 0.617021 (-1675 200);
PAINT SKYBLUE (-1675 200);
FORCEPROP 2 LAST CDS_LIB mstr_discrete
J 0
(-1650 300);
PAINT ORANGE (-1650 300);
DISPLAY INVISIBLE (-1650 300);
FORCEPROP 2 LAST SEC_TYPE 0805
J 0
(-1700 500);
DISPLAY 1.021277 (-1700 500);
PAINT ORANGE (-1700 500);
DISPLAY INVISIBLE (-1700 500);
FORCEPROP 2 LAST SEC 1
J 0
(-1700 500);
DISPLAY 0.680851 (-1700 500);
PAINT MONO (-1700 500);
DISPLAY INVISIBLE (-1700 500);
FORCEPROP 0 LAST ROOM HOT_SWAP
J 0
(-1700 500);
DISPLAY 1.021277 (-1700 500);
PAINT ORANGE (-1700 500);
DISPLAY INVISIBLE (-1700 500);
FORCEPROP 1 LAST PATH I19
J 0
(-1700 450);
DISPLAY 0.978723 (-1700 450);
PAINT WHITE (-1700 450);
DISPLAY INVISIBLE (-1700 450);
FORCEPROP 2 LAST CDS_LOCATION R1D41
J 0
(-1700 350);
DISPLAY 0.617021 (-1700 350);
PAINT AQUA (-1700 350);
DISPLAY INVISIBLE (-1700 350);
FORCEADD RES..2
(-5525 4025);
FORCEPROP 1 LAST LOCATION R9P30
J 0
(-5480 4150);
DISPLAY 0.617021 (-5480 4150);
PAINT AQUA (-5480 4150);
FORCEPROP 1 LAST WATTAGE 1/10W
J 0
(-5485 4000);
DISPLAY 0.617021 (-5485 4000);
PAINT SKYBLUE (-5485 4000);
FORCEPROP 1 LAST PACK_TYPE 0603
J 0
(-5485 3850);
DISPLAY 0.617021 (-5485 3850);
PAINT SKYBLUE (-5485 3850);
FORCEPROP 1 LAST PART_NUMBER G22026-041
J 0
(-5485 3900);
DISPLAY 0.617021 (-5485 3900);
PAINT BLUE (-5485 3900);
FORCEPROP 1 LAST MATERIAL CHIP
J 0
(-5485 3950);
DISPLAY 0.617021 (-5485 3950);
PAINT SKYBLUE (-5485 3950);
FORCEPROP 1 LAST VALUE 10.0
J 0
(-5480 4100);
DISPLAY 0.617021 (-5480 4100);
PAINT SKYBLUE (-5480 4100);
FORCEPROP 1 LASTPIN (-5525 3925) $PN 2
J 0
(-5520 3935);
DISPLAY 0.617021 (-5520 3935);
PAINT ORANGE (-5520 3935);
FORCEPROP 1 LASTPIN (-5525 4125) $PN 1
J 0
(-5520 4087);
DISPLAY 0.617021 (-5520 4087);
PAINT ORANGE (-5520 4087);
FORCEPROP 1 LAST TOLERANCE 1%
J 0
(-5480 4050);
DISPLAY 0.617021 (-5480 4050);
PAINT SKYBLUE (-5480 4050);
FORCEPROP 2 LAST SEC_TYPE 0603
J 0
(-5475 4250);
DISPLAY 1.021277 (-5475 4250);
PAINT ORANGE (-5475 4250);
DISPLAY INVISIBLE (-5475 4250);
FORCEPROP 2 LAST SEC 1
J 0
(-5475 4250);
DISPLAY 0.680851 (-5475 4250);
PAINT MONO (-5475 4250);
DISPLAY INVISIBLE (-5475 4250);
FORCEPROP 2 LAST CDS_LOCATION R9P30
J 0
(-5480 4150);
DISPLAY 0.617021 (-5480 4150);
PAINT AQUA (-5480 4150);
DISPLAY INVISIBLE (-5480 4150);
FORCEPROP 1 LAST PATH I2
J 0
(-5475 4200);
DISPLAY 0.978723 (-5475 4200);
PAINT WHITE (-5475 4200);
DISPLAY INVISIBLE (-5475 4200);
FORCEPROP 0 LAST ROOM HOT_SWAP
J 0
(-5475 4200);
DISPLAY 1.021277 (-5475 4200);
PAINT ORANGE (-5475 4200);
DISPLAY INVISIBLE (-5475 4200);
FORCEPROP 2 LAST CDS_LIB mstr_discrete
J 0
(-5525 4025);
PAINT ORANGE (-5525 4025);
DISPLAY INVISIBLE (-5525 4025);
FORCEADD GND..1
(-1950 150);
FORCEPROP 3 LASTPIN (-1950 200) SIG_NAME GND\g
J 0
(-1940 210);
DISPLAY 0.659574 (-1940 210);
PAINT MONO (-1940 210);
DISPLAY INVISIBLE (-1940 210);
FORCEPROP 1 LAST HDL_POWER GND
J 0
(-1950 300);
DISPLAY 0.638298 (-1950 300);
PAINT GREEN (-1950 300);
DISPLAY INVISIBLE (-1950 300);
FORCEPROP 1 LAST BODY_TYPE PLUMBING
J 0
(-1995 107);
DISPLAY 0.340426 (-1995 107);
PAINT GREEN (-1995 107);
DISPLAY INVISIBLE (-1995 107);
FORCEPROP 2 LAST CDS_LIB mstr_symbols
J 0
(-1950 150);
PAINT ORANGE (-1950 150);
DISPLAY INVISIBLE (-1950 150);
FORCEPROP 1 LAST SIZE 1B
J 0
(-1875 100);
DISPLAY 0.638298 (-1875 100);
PAINT GREEN (-1875 100);
DISPLAY INVISIBLE (-1875 100);
FORCEPROP 1 LAST VOLTAGE 0
J 0
(-1950 150);
PAINT SKYBLUE (-1950 150);
DISPLAY INVISIBLE (-1950 150);
FORCEPROP 1 LAST PATH I20
J 0
(-1875 150);
DISPLAY 0.872340 (-1875 150);
PAINT AQUA (-1875 150);
DISPLAY INVISIBLE (-1875 150);
FORCEADD AGND0..1
(-2000 2375);
FORCEPROP 3 LASTPIN (-2000 2425) SIG_NAME AGND_HSC\g
J 0
(-1990 2435);
DISPLAY 0.659574 (-1990 2435);
PAINT MONO (-1990 2435);
DISPLAY INVISIBLE (-1990 2435);
FORCEPROP 1 LAST HDL_POWER AGND_HSC
J 1
(-2000 2325);
DISPLAY 0.617021 (-2000 2325);
PAINT GREEN (-2000 2325);
FORCEPROP 1 LAST BODY_TYPE PLUMBING
J 0
(-2045 2332);
DISPLAY 0.340426 (-2045 2332);
PAINT GREEN (-2045 2332);
DISPLAY INVISIBLE (-2045 2332);
FORCEPROP 2 LAST CDS_LIB mstr_symbols
J 0
(-2000 2375);
PAINT ORANGE (-2000 2375);
DISPLAY INVISIBLE (-2000 2375);
FORCEPROP 1 LAST PATH I21
J 0
(-1925 2375);
DISPLAY 0.872340 (-1925 2375);
PAINT AQUA (-1925 2375);
DISPLAY INVISIBLE (-1925 2375);
FORCEPROP 2 LAST ROOM VR_P3V3
J 0
(-2025 2350);
PAINT ORANGE (-2025 2350);
DISPLAY INVISIBLE (-2025 2350);
FORCEPROP 2 LAST BOM_COST MIO_VRD_MAIN
J 0
(-1975 2350);
PAINT ORANGE (-1975 2350);
DISPLAY INVISIBLE (-1975 2350);
FORCEPROP 1 LAST VOLTAGE 0
J 0
(-2000 2375);
PAINT SKYBLUE (-2000 2375);
DISPLAY INVISIBLE (-2000 2375);
FORCEADD AGND0..1
(-4725 625);
FORCEPROP 3 LASTPIN (-4725 675) SIG_NAME AGND_HSC\g
J 0
(-4715 685);
DISPLAY 0.659574 (-4715 685);
PAINT MONO (-4715 685);
DISPLAY INVISIBLE (-4715 685);
FORCEPROP 1 LAST HDL_POWER AGND_HSC
J 1
(-4725 575);
DISPLAY 0.617021 (-4725 575);
PAINT GREEN (-4725 575);
FORCEPROP 1 LAST BODY_TYPE PLUMBING
J 0
(-4770 582);
DISPLAY 0.340426 (-4770 582);
PAINT GREEN (-4770 582);
DISPLAY INVISIBLE (-4770 582);
FORCEPROP 1 LAST VOLTAGE 0
J 0
(-4725 625);
PAINT SKYBLUE (-4725 625);
DISPLAY INVISIBLE (-4725 625);
FORCEPROP 2 LAST CDS_LIB mstr_symbols
J 0
(-4725 625);
PAINT ORANGE (-4725 625);
DISPLAY INVISIBLE (-4725 625);
FORCEPROP 2 LAST BOM_COST MIO_VRD_MAIN
J 0
(-4700 600);
PAINT ORANGE (-4700 600);
DISPLAY INVISIBLE (-4700 600);
FORCEPROP 1 LAST PATH I23
J 0
(-4650 625);
DISPLAY 0.872340 (-4650 625);
PAINT AQUA (-4650 625);
DISPLAY INVISIBLE (-4650 625);
FORCEPROP 2 LAST ROOM VR_P3V3
J 0
(-4750 600);
PAINT ORANGE (-4750 600);
DISPLAY INVISIBLE (-4750 600);
FORCEADD CAP..1
(-4850 1500);
FORCEPROP 1 LAST TOLERANCE 10%
J 0
(-4800 1450);
DISPLAY 0.617021 (-4800 1450);
PAINT SKYBLUE (-4800 1450);
FORCEPROP 1 LAST VALUE 0.033UF
J 0
(-4800 1550);
DISPLAY 0.617021 (-4800 1550);
PAINT SKYBLUE (-4800 1550);
FORCEPROP 1 LAST MATERIAL X7R
J 0
(-4800 1400);
DISPLAY 0.617021 (-4800 1400);
PAINT SKYBLUE (-4800 1400);
FORCEPROP 1 LASTPIN (-4850 1400) $PN 2
J 0
(-4840 1380);
DISPLAY 0.617021 (-4840 1380);
PAINT ORANGE (-4840 1380);
FORCEPROP 1 LAST VOLTAGE 50V
J 0
(-4800 1500);
DISPLAY 0.617021 (-4800 1500);
PAINT SKYBLUE (-4800 1500);
FORCEPROP 1 LAST LOCATION C9P14
J 0
(-4800 1600);
DISPLAY 0.617021 (-4800 1600);
PAINT AQUA (-4800 1600);
FORCEPROP 1 LAST PART_NUMBER 603269-064
J 0
(-4800 1350);
DISPLAY 0.617021 (-4800 1350);
PAINT BLUE (-4800 1350);
FORCEPROP 1 LASTPIN (-4850 1600) $PN 1
J 0
(-4840 1580);
DISPLAY 0.617021 (-4840 1580);
PAINT ORANGE (-4840 1580);
FORCEPROP 1 LAST PACK_TYPE 0603LF
J 0
(-4800 1300);
DISPLAY 0.617021 (-4800 1300);
PAINT SKYBLUE (-4800 1300);
FORCEPROP 1 LAST PATH I24
J 0
(-4800 1650);
DISPLAY 0.978723 (-4800 1650);
PAINT WHITE (-4800 1650);
DISPLAY INVISIBLE (-4800 1650);
FORCEPROP 2 LAST CDS_LIB mstr_discrete
J 0
(-4850 1500);
PAINT ORANGE (-4850 1500);
DISPLAY INVISIBLE (-4850 1500);
FORCEPROP 0 LAST ROOM HOT_SWAP
J 0
(-4800 1700);
DISPLAY 1.021277 (-4800 1700);
PAINT ORANGE (-4800 1700);
DISPLAY INVISIBLE (-4800 1700);
FORCEPROP 2 LAST CDS_LOCATION C9P14
J 0
(-4800 1600);
DISPLAY 0.617021 (-4800 1600);
PAINT AQUA (-4800 1600);
DISPLAY INVISIBLE (-4800 1600);
FORCEPROP 2 LAST SEC 1
J 0
(-4800 1700);
DISPLAY 0.680851 (-4800 1700);
PAINT MONO (-4800 1700);
DISPLAY INVISIBLE (-4800 1700);
FORCEPROP 2 LAST SEC_TYPE 0603LF
J 0
(-4800 1700);
DISPLAY 1.021277 (-4800 1700);
PAINT ORANGE (-4800 1700);
DISPLAY INVISIBLE (-4800 1700);
FORCEADD RES..2
(-4625 1025);
FORCEPROP 1 LASTPIN (-4625 1125) $PN 1
J 0
(-4620 1087);
DISPLAY 0.617021 (-4620 1087);
PAINT ORANGE (-4620 1087);
FORCEPROP 1 LASTPIN (-4625 925) $PN 2
J 0
(-4620 935);
DISPLAY 0.617021 (-4620 935);
PAINT ORANGE (-4620 935);
FORCEPROP 1 LAST WATTAGE 1/16W
J 0
(-4585 1000);
DISPLAY 0.617021 (-4585 1000);
PAINT SKYBLUE (-4585 1000);
FORCEPROP 1 LAST MATERIAL EMPTY
J 0
(-4585 950);
DISPLAY 0.617021 (-4585 950);
PAINT RED (-4585 950);
FORCEPROP 1 LAST LOCATION R1D28
J 0
(-4580 1150);
DISPLAY 0.617021 (-4580 1150);
PAINT AQUA (-4580 1150);
FORCEPROP 1 LAST VALUE 100.0
J 0
(-4580 1100);
DISPLAY 0.617021 (-4580 1100);
PAINT SKYBLUE (-4580 1100);
FORCEPROP 1 LAST TOLERANCE 1%
J 0
(-4580 1050);
DISPLAY 0.617021 (-4580 1050);
PAINT SKYBLUE (-4580 1050);
FORCEPROP 1 LAST PACK_TYPE 0402
J 0
(-4585 850);
DISPLAY 0.617021 (-4585 850);
PAINT SKYBLUE (-4585 850);
FORCEPROP 1 LAST PART_NUMBER G21796-017
J 0
(-4585 900);
DISPLAY 0.617021 (-4585 900);
PAINT BLUE (-4585 900);
FORCEPROP 0 LAST ROOM HOT_SWAP
J 0
(-4575 1250);
DISPLAY 1.021277 (-4575 1250);
PAINT ORANGE (-4575 1250);
DISPLAY INVISIBLE (-4575 1250);
FORCEPROP 2 LAST SEC_TYPE 0402
J 0
(-4575 1250);
DISPLAY 1.021277 (-4575 1250);
PAINT ORANGE (-4575 1250);
DISPLAY INVISIBLE (-4575 1250);
FORCEPROP 1 LAST PATH I26
J 0
(-4575 1200);
DISPLAY 0.978723 (-4575 1200);
PAINT WHITE (-4575 1200);
DISPLAY INVISIBLE (-4575 1200);
FORCEPROP 2 LAST CDS_LOCATION R1D28
J 0
(-4580 1150);
DISPLAY 0.617021 (-4580 1150);
PAINT AQUA (-4580 1150);
DISPLAY INVISIBLE (-4580 1150);
FORCEPROP 2 LAST SEC 1
J 0
(-4575 1250);
DISPLAY 0.680851 (-4575 1250);
PAINT MONO (-4575 1250);
DISPLAY INVISIBLE (-4575 1250);
FORCEPROP 2 LAST CDS_LIB mstr_discrete
J 0
(-4625 1025);
PAINT ORANGE (-4625 1025);
DISPLAY INVISIBLE (-4625 1025);
FORCEADD RES..1
(-5600 2725);
FORCEPROP 1 LAST MATERIAL CHIP
J 0
(-5450 2775);
DISPLAY 0.617021 (-5450 2775);
PAINT SKYBLUE (-5450 2775);
FORCEPROP 1 LAST PART_NUMBER G21497-005
J 0
(-5450 2725);
DISPLAY 0.638298 (-5450 2725);
PAINT BLUE (-5450 2725);
FORCEPROP 1 LASTPIN (-5500 2725) $PN 2
J 0
(-5538 2737);
DISPLAY 0.617021 (-5538 2737);
PAINT ORANGE (-5538 2737);
FORCEPROP 1 LASTPIN (-5700 2725) $PN 1
J 0
(-5688 2737);
DISPLAY 0.617021 (-5688 2737);
PAINT ORANGE (-5688 2737);
FORCEPROP 1 LAST TOLERANCE 5%
J 0
(-5700 2775);
DISPLAY 0.638298 (-5700 2775);
PAINT SKYBLUE (-5700 2775);
FORCEPROP 1 LAST WATTAGE 1/16W
J 0
(-5600 2775);
DISPLAY 0.638298 (-5600 2775);
PAINT SKYBLUE (-5600 2775);
FORCEPROP 1 LAST VALUE 0.0
J 0
(-5800 2775);
DISPLAY 0.617021 (-5800 2775);
PAINT SKYBLUE (-5800 2775);
FORCEPROP 1 LAST PACK_TYPE 0402
J 0
(-5300 2775);
DISPLAY 0.638298 (-5300 2775);
PAINT SKYBLUE (-5300 2775);
FORCEPROP 1 LAST LOCATION R1D24
J 0
(-5950 2775);
DISPLAY 0.617021 (-5950 2775);
PAINT AQUA (-5950 2775);
FORCEPROP 2 LAST CDS_LOCATION R1D24
J 0
(-5350 2775);
DISPLAY 0.617021 (-5350 2775);
PAINT AQUA (-5350 2775);
DISPLAY INVISIBLE (-5350 2775);
FORCEPROP 2 LAST CDS_LIB mstr_discrete
J 0
(-5600 2725);
PAINT ORANGE (-5600 2725);
DISPLAY INVISIBLE (-5600 2725);
FORCEPROP 2 LAST SEC_TYPE 0402
J 0
(-5650 2925);
DISPLAY 1.021277 (-5650 2925);
PAINT ORANGE (-5650 2925);
DISPLAY INVISIBLE (-5650 2925);
FORCEPROP 2 LAST SEC 1
J 0
(-5650 2925);
DISPLAY 0.680851 (-5650 2925);
PAINT MONO (-5650 2925);
DISPLAY INVISIBLE (-5650 2925);
FORCEPROP 1 LAST PATH I27
J 0
(-5650 2875);
DISPLAY 0.978723 (-5650 2875);
PAINT WHITE (-5650 2875);
DISPLAY INVISIBLE (-5650 2875);
FORCEPROP 0 LAST ROOM HOT_SWAP
J 0
(-5650 2925);
DISPLAY 1.021277 (-5650 2925);
PAINT ORANGE (-5650 2925);
DISPLAY INVISIBLE (-5650 2925);
FORCEADD RES..1
(-5600 2675);
FORCEPROP 1 LAST PART_NUMBER G21497-005
J 0
(-5450 2675);
DISPLAY 0.617021 (-5450 2675);
PAINT BLUE (-5450 2675);
FORCEPROP 1 LAST PACK_TYPE 0402
J 0
(-5300 2625);
DISPLAY 0.617021 (-5300 2625);
PAINT SKYBLUE (-5300 2625);
FORCEPROP 1 LASTPIN (-5500 2675) $PN 2
J 0
(-5538 2687);
DISPLAY 0.617021 (-5538 2687);
PAINT ORANGE (-5538 2687);
FORCEPROP 1 LASTPIN (-5700 2675) $PN 1
J 0
(-5688 2687);
DISPLAY 0.617021 (-5688 2687);
PAINT ORANGE (-5688 2687);
FORCEPROP 1 LAST TOLERANCE 5%
J 0
(-5700 2625);
DISPLAY 0.617021 (-5700 2625);
PAINT SKYBLUE (-5700 2625);
FORCEPROP 1 LAST MATERIAL CHIP
J 0
(-5450 2625);
DISPLAY 0.617021 (-5450 2625);
PAINT SKYBLUE (-5450 2625);
FORCEPROP 1 LAST WATTAGE 1/16W
J 2
(-5475 2625);
DISPLAY 0.617021 (-5475 2625);
PAINT SKYBLUE (-5475 2625);
FORCEPROP 1 LAST LOCATION R1D25
J 0
(-5950 2625);
DISPLAY 0.617021 (-5950 2625);
PAINT AQUA (-5950 2625);
FORCEPROP 1 LAST VALUE 0.0
J 2
(-5750 2625);
DISPLAY 0.617021 (-5750 2625);
PAINT SKYBLUE (-5750 2625);
FORCEPROP 2 LAST CDS_LOCATION R1D25
J 0
(-5350 2725);
DISPLAY 0.617021 (-5350 2725);
PAINT AQUA (-5350 2725);
DISPLAY INVISIBLE (-5350 2725);
FORCEPROP 2 LAST CDS_LIB mstr_discrete
J 0
(-5600 2675);
PAINT ORANGE (-5600 2675);
DISPLAY INVISIBLE (-5600 2675);
FORCEPROP 2 LAST SEC_TYPE 0402
J 0
(-5650 2875);
DISPLAY 1.021277 (-5650 2875);
PAINT ORANGE (-5650 2875);
DISPLAY INVISIBLE (-5650 2875);
FORCEPROP 2 LAST SEC 1
J 0
(-5650 2875);
DISPLAY 0.680851 (-5650 2875);
PAINT MONO (-5650 2875);
DISPLAY INVISIBLE (-5650 2875);
FORCEPROP 1 LAST PATH I28
J 0
(-5650 2825);
DISPLAY 0.978723 (-5650 2825);
PAINT WHITE (-5650 2825);
DISPLAY INVISIBLE (-5650 2825);
FORCEPROP 0 LAST ROOM HOT_SWAP
J 0
(-5650 2825);
DISPLAY 1.021277 (-5650 2825);
PAINT ORANGE (-5650 2825);
DISPLAY INVISIBLE (-5650 2825);
FORCEADD CAP..1
(-5525 3600);
FORCEPROP 1 LAST LOCATION C1D25
J 0
(-5475 3700);
DISPLAY 0.617021 (-5475 3700);
PAINT AQUA (-5475 3700);
FORCEPROP 1 LAST VALUE 1.0UF
J 0
(-5475 3650);
DISPLAY 0.617021 (-5475 3650);
PAINT SKYBLUE (-5475 3650);
FORCEPROP 1 LAST VOLTAGE 16V
J 0
(-5475 3600);
DISPLAY 0.617021 (-5475 3600);
PAINT SKYBLUE (-5475 3600);
FORCEPROP 1 LAST PART_NUMBER D97712-011
J 0
(-5475 3450);
DISPLAY 0.617021 (-5475 3450);
PAINT BLUE (-5475 3450);
FORCEPROP 1 LAST MATERIAL X6S
J 0
(-5475 3500);
DISPLAY 0.617021 (-5475 3500);
PAINT SKYBLUE (-5475 3500);
FORCEPROP 1 LASTPIN (-5525 3700) $PN 1
J 0
(-5515 3680);
DISPLAY 0.617021 (-5515 3680);
PAINT ORANGE (-5515 3680);
FORCEPROP 1 LAST PACK_TYPE 0402
J 0
(-5475 3400);
DISPLAY 0.617021 (-5475 3400);
PAINT SKYBLUE (-5475 3400);
FORCEPROP 1 LASTPIN (-5525 3500) $PN 2
J 0
(-5515 3480);
DISPLAY 0.617021 (-5515 3480);
PAINT ORANGE (-5515 3480);
FORCEPROP 1 LAST TOLERANCE 10%
J 0
(-5475 3550);
DISPLAY 0.617021 (-5475 3550);
PAINT SKYBLUE (-5475 3550);
FORCEPROP 2 LAST SEC_TYPE 0402
J 0
(-5475 3800);
DISPLAY 1.021277 (-5475 3800);
PAINT ORANGE (-5475 3800);
DISPLAY INVISIBLE (-5475 3800);
FORCEPROP 0 LAST ROOM HOT_SWAP
J 0
(-5475 3750);
DISPLAY 1.021277 (-5475 3750);
PAINT ORANGE (-5475 3750);
DISPLAY INVISIBLE (-5475 3750);
FORCEPROP 1 LAST PATH I3
J 0
(-5475 3750);
DISPLAY 0.978723 (-5475 3750);
PAINT WHITE (-5475 3750);
DISPLAY INVISIBLE (-5475 3750);
FORCEPROP 2 LAST CDS_LOCATION C1D25
J 0
(-5475 3700);
DISPLAY 0.617021 (-5475 3700);
PAINT AQUA (-5475 3700);
DISPLAY INVISIBLE (-5475 3700);
FORCEPROP 2 LAST SEC 1
J 0
(-5475 3800);
DISPLAY 0.680851 (-5475 3800);
PAINT MONO (-5475 3800);
DISPLAY INVISIBLE (-5475 3800);
FORCEPROP 2 LAST CDS_LIB mstr_discrete
J 0
(-5525 3600);
PAINT MONO (-5525 3600);
DISPLAY INVISIBLE (-5525 3600);
FORCEADD OFFPAGE..4
R 2
(-6750 2725);
FORCEPROP 2 LAST $XR3 247 
J 0
(-7392 2725);
DISPLAY 0.638298 (-7392 2725);
PAINT MONO (-7392 2725);
FORCEPROP 2 LAST $XR2 181 
J 0
(-7272 2725);
DISPLAY 0.638298 (-7272 2725);
PAINT MONO (-7272 2725);
FORCEPROP 2 LAST $XR1 159 
J 0
(-7152 2725);
DISPLAY 0.638298 (-7152 2725);
PAINT MONO (-7152 2725);
FORCEPROP 2 LAST $XR0 138 
J 0
(-7032 2725);
DISPLAY 0.638298 (-7032 2725);
PAINT MONO (-7032 2725);
FORCEPROP 1 LAST COMMENT_BODY TRUE
J 2
(-6725 2625);
DISPLAY 1.872340 (-6725 2625);
PAINT GREEN (-6725 2625);
DISPLAY INVISIBLE (-6725 2625);
FORCEPROP 1 LAST OFFPAGE TRUE
J 2
(-7075 2600);
PAINT GREEN (-7075 2600);
DISPLAY INVISIBLE (-7075 2600);
FORCEPROP 2 LAST PATH I30
J 0
(-6700 2800);
DISPLAY 1.021277 (-6700 2800);
PAINT ORANGE (-6700 2800);
DISPLAY INVISIBLE (-6700 2800);
FORCEPROP 2 LAST CDS_LIB mstr_standard
J 0
(-6750 2725);
PAINT ORANGE (-6750 2725);
DISPLAY INVISIBLE (-6750 2725);
FORCEADD OFFPAGE..3
R 2
(-6750 2675);
FORCEPROP 2 LAST $XR2 181 
J 0
(-7270 2675);
DISPLAY 0.638298 (-7270 2675);
PAINT MONO (-7270 2675);
FORCEPROP 2 LAST $XR1 159 
J 0
(-7150 2675);
DISPLAY 0.638298 (-7150 2675);
PAINT MONO (-7150 2675);
FORCEPROP 2 LAST $XR0 138 
J 0
(-7030 2675);
DISPLAY 0.638298 (-7030 2675);
PAINT MONO (-7030 2675);
FORCEPROP 2 LAST $XR3 247 
J 0
(-7390 2675);
DISPLAY 0.638298 (-7390 2675);
PAINT MONO (-7390 2675);
FORCEPROP 1 LAST COMMENT_BODY TRUE
J 2
(-6700 2575);
DISPLAY 0.872340 (-6700 2575);
PAINT GREEN (-6700 2575);
DISPLAY INVISIBLE (-6700 2575);
FORCEPROP 1 LAST OFFPAGE TRUE
J 2
(-7075 2550);
DISPLAY 0.872340 (-7075 2550);
PAINT GREEN (-7075 2550);
DISPLAY INVISIBLE (-7075 2550);
FORCEPROP 2 LAST PATH I31
J 0
(-6700 2750);
DISPLAY 1.021277 (-6700 2750);
PAINT ORANGE (-6700 2750);
DISPLAY INVISIBLE (-6700 2750);
FORCEPROP 2 LAST CDS_LIB mstr_standard
J 0
(-6750 2675);
PAINT ORANGE (-6750 2675);
DISPLAY INVISIBLE (-6750 2675);
FORCEADD RES..2
(-8000 2375);
FORCEPROP 1 LAST LOCATION R9P17
J 0
(-7980 2525);
DISPLAY 0.617021 (-7980 2525);
PAINT AQUA (-7980 2525);
FORCEPROP 1 LAST WATTAGE 1/16W
J 0
(-7960 2425);
DISPLAY 0.617021 (-7960 2425);
PAINT SKYBLUE (-7960 2425);
FORCEPROP 1 LAST PART_NUMBER G21796-109
J 0
(-7985 2325);
DISPLAY 0.617021 (-7985 2325);
PAINT BLUE (-7985 2325);
FORCEPROP 1 LAST MATERIAL CHIP
J 0
(-7960 2375);
DISPLAY 0.617021 (-7960 2375);
PAINT SKYBLUE (-7960 2375);
FORCEPROP 1 LAST PACK_TYPE 0402
J 0
(-7960 2275);
DISPLAY 0.617021 (-7960 2275);
PAINT SKYBLUE (-7960 2275);
FORCEPROP 1 LAST VALUE 150.0K
J 0
(-7980 2225);
DISPLAY 0.617021 (-7980 2225);
PAINT SKYBLUE (-7980 2225);
FORCEPROP 1 LAST TOLERANCE 1%
J 0
(-7955 2475);
DISPLAY 0.617021 (-7955 2475);
PAINT SKYBLUE (-7955 2475);
FORCEPROP 1 LASTPIN (-8000 2475) $PN 1
J 0
(-7995 2437);
DISPLAY 0.617021 (-7995 2437);
PAINT ORANGE (-7995 2437);
FORCEPROP 1 LASTPIN (-8000 2275) $PN 2
J 0
(-7995 2285);
DISPLAY 0.617021 (-7995 2285);
PAINT ORANGE (-7995 2285);
FORCEPROP 2 LAST SEC 1
J 0
(-7950 2600);
DISPLAY 0.680851 (-7950 2600);
PAINT MONO (-7950 2600);
DISPLAY INVISIBLE (-7950 2600);
FORCEPROP 2 LAST SEC_TYPE 0402
J 0
(-7950 2600);
DISPLAY 1.021277 (-7950 2600);
PAINT ORANGE (-7950 2600);
DISPLAY INVISIBLE (-7950 2600);
FORCEPROP 1 LAST PATH I33
J 0
(-7950 2550);
DISPLAY 0.978723 (-7950 2550);
PAINT WHITE (-7950 2550);
DISPLAY INVISIBLE (-7950 2550);
FORCEPROP 0 LAST ROOM HOT_SWAP
J 0
(-8050 2525);
DISPLAY 1.021277 (-8050 2525);
PAINT ORANGE (-8050 2525);
DISPLAY INVISIBLE (-8050 2525);
FORCEPROP 2 LAST CDS_LIB mstr_discrete
J 0
(-8000 2375);
PAINT ORANGE (-8000 2375);
DISPLAY INVISIBLE (-8000 2375);
FORCEPROP 2 LAST CDS_LOCATION R9P17
J 0
(-7980 2525);
DISPLAY 0.617021 (-7980 2525);
PAINT AQUA (-7980 2525);
DISPLAY INVISIBLE (-7980 2525);
FORCEADD AGND0..1
(-7675 2075);
FORCEPROP 3 LASTPIN (-7675 2125) SIG_NAME AGND_HSC\g
J 0
(-7665 2135);
DISPLAY 0.659574 (-7665 2135);
PAINT MONO (-7665 2135);
DISPLAY INVISIBLE (-7665 2135);
FORCEPROP 1 LAST HDL_POWER AGND_HSC
J 1
(-7675 2025);
DISPLAY 0.617021 (-7675 2025);
PAINT GREEN (-7675 2025);
FORCEPROP 2 LAST ROOM VR_P3V3
J 0
(-7700 2050);
PAINT ORANGE (-7700 2050);
DISPLAY INVISIBLE (-7700 2050);
FORCEPROP 1 LAST PATH I34
J 0
(-7600 2075);
DISPLAY 0.872340 (-7600 2075);
PAINT AQUA (-7600 2075);
DISPLAY INVISIBLE (-7600 2075);
FORCEPROP 2 LAST BOM_COST MIO_VRD_MAIN
J 0
(-7650 2050);
PAINT ORANGE (-7650 2050);
DISPLAY INVISIBLE (-7650 2050);
FORCEPROP 2 LAST CDS_LIB mstr_symbols
J 0
(-7675 2075);
PAINT ORANGE (-7675 2075);
DISPLAY INVISIBLE (-7675 2075);
FORCEPROP 1 LAST VOLTAGE 0
J 0
(-7675 2075);
PAINT SKYBLUE (-7675 2075);
DISPLAY INVISIBLE (-7675 2075);
FORCEPROP 1 LAST BODY_TYPE PLUMBING
J 0
(-7720 2032);
DISPLAY 0.340426 (-7720 2032);
PAINT GREEN (-7720 2032);
DISPLAY INVISIBLE (-7720 2032);
FORCEADD RES..2
(-7675 2375);
FORCEPROP 0 LAST BOM_DS NOPOP
J 0
(-7625 2125);
DISPLAY 0.638298 (-7625 2125);
PAINT BROWN (-7625 2125);
DISPLAY BOTH (-7625 2125);
FORCEPROP 1 LAST PART_NUMBER G21497-005
J 0
(-7635 2225);
DISPLAY 0.617021 (-7635 2225);
PAINT BLUE (-7635 2225);
FORCEPROP 1 LAST VALUE 0.0
J 0
(-7630 2425);
DISPLAY 0.617021 (-7630 2425);
PAINT SKYBLUE (-7630 2425);
FORCEPROP 1 LAST TOLERANCE 5%
J 0
(-7630 2375);
DISPLAY 0.617021 (-7630 2375);
PAINT SKYBLUE (-7630 2375);
FORCEPROP 1 LAST WATTAGE 1/16W
J 0
(-7635 2325);
DISPLAY 0.617021 (-7635 2325);
PAINT SKYBLUE (-7635 2325);
FORCEPROP 1 LAST MATERIAL CHIP
J 0
(-7635 2275);
DISPLAY 0.617021 (-7635 2275);
PAINT SKYBLUE (-7635 2275);
FORCEPROP 1 LAST PACK_TYPE 0402
J 0
(-7635 2175);
DISPLAY 0.617021 (-7635 2175);
PAINT SKYBLUE (-7635 2175);
FORCEPROP 1 LASTPIN (-7675 2475) $PN 1
J 0
(-7670 2437);
DISPLAY 0.617021 (-7670 2437);
PAINT ORANGE (-7670 2437);
FORCEPROP 1 LASTPIN (-7675 2275) $PN 2
J 0
(-7670 2285);
DISPLAY 0.617021 (-7670 2285);
PAINT ORANGE (-7670 2285);
FORCEPROP 1 LAST LOCATION R9P16
J 0
(-7630 2475);
DISPLAY 0.617021 (-7630 2475);
PAINT AQUA (-7630 2475);
FORCEPROP 2 LAST SEC_TYPE 0402
J 0
(-7625 2600);
DISPLAY 1.021277 (-7625 2600);
PAINT ORANGE (-7625 2600);
DISPLAY INVISIBLE (-7625 2600);
FORCEPROP 2 LAST SEC 1
J 0
(-7625 2600);
DISPLAY 0.680851 (-7625 2600);
PAINT MONO (-7625 2600);
DISPLAY INVISIBLE (-7625 2600);
FORCEPROP 1 LAST PATH I36
J 0
(-7625 2550);
DISPLAY 0.978723 (-7625 2550);
PAINT WHITE (-7625 2550);
DISPLAY INVISIBLE (-7625 2550);
FORCEPROP 2 LAST CDS_LIB mstr_discrete
J 0
(-7675 2375);
PAINT ORANGE (-7675 2375);
DISPLAY INVISIBLE (-7675 2375);
FORCEPROP 2 LAST CDS_LOCATION R9P16
J 0
(-7630 2475);
DISPLAY 0.617021 (-7630 2475);
PAINT AQUA (-7630 2475);
DISPLAY INVISIBLE (-7630 2475);
FORCEPROP 0 LAST ROOM HOT_SWAP
J 0
(-7725 2525);
DISPLAY 1.021277 (-7725 2525);
PAINT ORANGE (-7725 2525);
DISPLAY INVISIBLE (-7725 2525);
FORCEADD RES..2
(-7675 2950);
FORCEPROP 1 LAST PART_NUMBER G21796-072
J 0
(-7635 2825);
DISPLAY 0.617021 (-7635 2825);
PAINT BLUE (-7635 2825);
FORCEPROP 1 LAST VALUE 4.75K
J 0
(-7605 3025);
DISPLAY 0.617021 (-7605 3025);
PAINT SKYBLUE (-7605 3025);
FORCEPROP 1 LAST LOCATION R1D27
J 0
(-7630 3075);
DISPLAY 0.617021 (-7630 3075);
PAINT AQUA (-7630 3075);
FORCEPROP 1 LAST TOLERANCE 1%
J 0
(-7505 2975);
DISPLAY 0.617021 (-7505 2975);
PAINT SKYBLUE (-7505 2975);
FORCEPROP 1 LASTPIN (-7675 3050) $PN 1
J 0
(-7670 3012);
DISPLAY 0.617021 (-7670 3012);
PAINT ORANGE (-7670 3012);
FORCEPROP 1 LASTPIN (-7675 2850) $PN 2
J 0
(-7670 2860);
DISPLAY 0.617021 (-7670 2860);
PAINT ORANGE (-7670 2860);
FORCEPROP 1 LAST PACK_TYPE 0402
J 0
(-7635 2775);
DISPLAY 0.617021 (-7635 2775);
PAINT SKYBLUE (-7635 2775);
FORCEPROP 1 LAST MATERIAL EMPTY
J 0
(-7560 2875);
DISPLAY 0.617021 (-7560 2875);
PAINT RED (-7560 2875);
FORCEPROP 1 LAST WATTAGE 1/16W
J 0
(-7535 2925);
DISPLAY 0.617021 (-7535 2925);
PAINT SKYBLUE (-7535 2925);
FORCEPROP 2 LAST CDS_LIB mstr_discrete
J 0
(-7675 2950);
PAINT ORANGE (-7675 2950);
DISPLAY INVISIBLE (-7675 2950);
FORCEPROP 1 LAST PATH I38
J 0
(-7625 3125);
DISPLAY 0.978723 (-7625 3125);
PAINT WHITE (-7625 3125);
DISPLAY INVISIBLE (-7625 3125);
FORCEPROP 2 LAST CDS_LOCATION R1D27
J 0
(-7630 3075);
DISPLAY 0.617021 (-7630 3075);
PAINT AQUA (-7630 3075);
DISPLAY INVISIBLE (-7630 3075);
FORCEPROP 2 LAST SEC_TYPE 0402
J 0
(-7625 3175);
DISPLAY 1.021277 (-7625 3175);
PAINT ORANGE (-7625 3175);
DISPLAY INVISIBLE (-7625 3175);
FORCEPROP 2 LAST SEC 1
J 0
(-7625 3175);
DISPLAY 0.680851 (-7625 3175);
PAINT MONO (-7625 3175);
DISPLAY INVISIBLE (-7625 3175);
FORCEPROP 0 LAST NO_XNET_CONNECTION 1
J 0
(-7625 3175);
PAINT MONO (-7625 3175);
DISPLAY INVISIBLE (-7625 3175);
FORCEPROP 0 LAST ROOM HOT_SWAP
J 0
(-7625 3175);
DISPLAY 1.021277 (-7625 3175);
PAINT ORANGE (-7625 3175);
DISPLAY INVISIBLE (-7625 3175);
FORCEADD RES..2
R 2
(-3125 1075);
FORCEPROP 1 LAST TOLERANCE 1%
J 2
(-3170 1100);
DISPLAY 0.617021 (-3170 1100);
PAINT SKYBLUE (-3170 1100);
FORCEPROP 1 LAST PACK_TYPE 0402
J 2
(-3265 1050);
DISPLAY 0.617021 (-3265 1050);
PAINT SKYBLUE (-3265 1050);
FORCEPROP 1 LASTPIN (-3125 1175) $PN 1
J 2
(-3130 1137);
DISPLAY 0.617021 (-3130 1137);
PAINT ORANGE (-3130 1137);
FORCEPROP 1 LAST LOCATION R9P18
J 2
(-3145 1200);
DISPLAY 0.617021 (-3145 1200);
PAINT AQUA (-3145 1200);
FORCEPROP 1 LAST WATTAGE 1/16W
J 2
(-3165 1050);
DISPLAY 0.617021 (-3165 1050);
PAINT SKYBLUE (-3165 1050);
FORCEPROP 1 LAST MATERIAL CHIP
J 2
(-3165 1000);
DISPLAY 0.617021 (-3165 1000);
PAINT SKYBLUE (-3165 1000);
FORCEPROP 1 LASTPIN (-3125 975) $PN 2
J 2
(-3130 985);
DISPLAY 0.617021 (-3130 985);
PAINT ORANGE (-3130 985);
FORCEPROP 1 LAST PART_NUMBER G21796-107
J 2
(-3140 950);
DISPLAY 0.617021 (-3140 950);
PAINT BLUE (-3140 950);
FORCEPROP 1 LAST VALUE 15.0K
J 2
(-3170 1150);
DISPLAY 0.617021 (-3170 1150);
PAINT SKYBLUE (-3170 1150);
FORCEPROP 2 LAST SEC_TYPE 0402
J 0
(-3175 1300);
DISPLAY 1.021277 (-3175 1300);
PAINT ORANGE (-3175 1300);
DISPLAY INVISIBLE (-3175 1300);
FORCEPROP 2 LAST SEC 1
J 0
(-3175 1300);
DISPLAY 0.680851 (-3175 1300);
PAINT MONO (-3175 1300);
DISPLAY INVISIBLE (-3175 1300);
FORCEPROP 2 LAST BOM_COST MIO_USB
J 2
(-3175 1250);
PAINT MONO (-3175 1250);
DISPLAY INVISIBLE (-3175 1250);
FORCEPROP 1 LAST PATH I41
J 2
(-3175 1250);
DISPLAY 0.978723 (-3175 1250);
PAINT WHITE (-3175 1250);
DISPLAY INVISIBLE (-3175 1250);
FORCEPROP 2 LAST ROOM HOT_SWAP
J 2
(-3175 1250);
PAINT PEACH (-3175 1250);
DISPLAY INVISIBLE (-3175 1250);
FORCEPROP 2 LAST CDS_LOCATION R9P18
J 2
(-3145 1200);
DISPLAY 0.617021 (-3145 1200);
PAINT AQUA (-3145 1200);
DISPLAY INVISIBLE (-3145 1200);
FORCEPROP 2 LAST CDS_LIB mstr_discrete
J 2
(-3125 1075);
PAINT ORANGE (-3125 1075);
DISPLAY INVISIBLE (-3125 1075);
FORCEADD RES..2
R 2
(-2825 750);
FORCEPROP 1 LAST WATTAGE 1/16W
J 2
(-2865 725);
DISPLAY 0.617021 (-2865 725);
PAINT SKYBLUE (-2865 725);
FORCEPROP 1 LASTPIN (-2825 850) $PN 1
J 2
(-2830 812);
DISPLAY 0.617021 (-2830 812);
PAINT ORANGE (-2830 812);
FORCEPROP 1 LASTPIN (-2825 650) $PN 2
J 2
(-2830 660);
DISPLAY 0.617021 (-2830 660);
PAINT ORANGE (-2830 660);
FORCEPROP 1 LAST PART_NUMBER G21796-161
J 2
(-2865 625);
DISPLAY 0.617021 (-2865 625);
PAINT BLUE (-2865 625);
FORCEPROP 1 LAST LOCATION R1D31
J 2
(-2970 850);
DISPLAY 0.617021 (-2970 850);
PAINT AQUA (-2970 850);
FORCEPROP 1 LAST VALUE 6.19K
J 2
(-2870 825);
DISPLAY 0.617021 (-2870 825);
PAINT SKYBLUE (-2870 825);
FORCEPROP 1 LAST TOLERANCE 1%
J 2
(-2870 775);
DISPLAY 0.617021 (-2870 775);
PAINT SKYBLUE (-2870 775);
FORCEPROP 1 LAST MATERIAL CHIP
J 2
(-2865 675);
DISPLAY 0.617021 (-2865 675);
PAINT SKYBLUE (-2865 675);
FORCEPROP 1 LAST PACK_TYPE 0402
J 2
(-2865 575);
DISPLAY 0.617021 (-2865 575);
PAINT SKYBLUE (-2865 575);
FORCEPROP 1 LAST PATH I43
J 2
(-2875 925);
DISPLAY 0.978723 (-2875 925);
PAINT WHITE (-2875 925);
DISPLAY INVISIBLE (-2875 925);
FORCEPROP 0 LAST ROOM HOT_SWAP
J 2
(-2875 975);
DISPLAY 1.021277 (-2875 975);
PAINT ORANGE (-2875 975);
DISPLAY INVISIBLE (-2875 975);
FORCEPROP 2 LAST SEC 1
J 0
(-2875 975);
DISPLAY 0.680851 (-2875 975);
PAINT MONO (-2875 975);
DISPLAY INVISIBLE (-2875 975);
FORCEPROP 2 LAST SEC_TYPE 0402
J 0
(-2875 975);
DISPLAY 1.021277 (-2875 975);
PAINT ORANGE (-2875 975);
DISPLAY INVISIBLE (-2875 975);
FORCEPROP 2 LAST CDS_LOCATION R1D31
J 2
(-2970 850);
DISPLAY 0.617021 (-2970 850);
PAINT AQUA (-2970 850);
DISPLAY INVISIBLE (-2970 850);
FORCEPROP 2 LAST CDS_LIB mstr_discrete
J 2
(-2825 750);
PAINT ORANGE (-2825 750);
DISPLAY INVISIBLE (-2825 750);
FORCEADD GND..1
(-2825 550);
FORCEPROP 3 LASTPIN (-2825 600) SIG_NAME GND\g
J 0
(-2815 610);
DISPLAY 0.659574 (-2815 610);
PAINT MONO (-2815 610);
DISPLAY INVISIBLE (-2815 610);
FORCEPROP 1 LAST HDL_POWER GND
J 0
(-2825 700);
DISPLAY 0.638298 (-2825 700);
PAINT GREEN (-2825 700);
DISPLAY INVISIBLE (-2825 700);
FORCEPROP 1 LAST BODY_TYPE PLUMBING
J 0
(-2870 507);
DISPLAY 0.340426 (-2870 507);
PAINT GREEN (-2870 507);
DISPLAY INVISIBLE (-2870 507);
FORCEPROP 1 LAST VOLTAGE 0
J 0
(-2825 550);
PAINT SKYBLUE (-2825 550);
DISPLAY INVISIBLE (-2825 550);
FORCEPROP 1 LAST SIZE 1B
J 0
(-2750 500);
DISPLAY 0.638298 (-2750 500);
PAINT GREEN (-2750 500);
DISPLAY INVISIBLE (-2750 500);
FORCEPROP 1 LAST PATH I44
J 0
(-2750 550);
DISPLAY 0.872340 (-2750 550);
PAINT AQUA (-2750 550);
DISPLAY INVISIBLE (-2750 550);
FORCEPROP 2 LAST CDS_LIB mstr_symbols
J 0
(-2825 550);
PAINT ORANGE (-2825 550);
DISPLAY INVISIBLE (-2825 550);
FORCEADD OFFPAGE..2
(-750 925);
FORCEPROP 2 LAST $XR0 196 
J 0
(-561 925);
DISPLAY 0.638298 (-561 925);
PAINT MONO (-561 925);
FORCEPROP 1 LAST COMMENT_BODY TRUE
J 0
(-795 830);
DISPLAY 0.872340 (-795 830);
PAINT GREEN (-795 830);
DISPLAY INVISIBLE (-795 830);
FORCEPROP 1 LAST OFFPAGE TRUE
J 0
(-425 800);
DISPLAY 0.872340 (-425 800);
PAINT GREEN (-425 800);
DISPLAY INVISIBLE (-425 800);
FORCEPROP 2 LAST PATH I45
J 0
(-575 1000);
DISPLAY 1.021277 (-575 1000);
PAINT ORANGE (-575 1000);
DISPLAY INVISIBLE (-575 1000);
FORCEPROP 2 LAST CDS_LIB mstr_standard
J 0
(-750 925);
PAINT ORANGE (-750 925);
DISPLAY INVISIBLE (-750 925);
FORCEADD OFFPAGE..2
(-750 1375);
FORCEPROP 2 LAST $XR2 146 
J 0
(-321 1375);
DISPLAY 0.638298 (-321 1375);
PAINT MONO (-321 1375);
FORCEPROP 2 LAST $XR1 119 
J 0
(-441 1375);
DISPLAY 0.638298 (-441 1375);
PAINT MONO (-441 1375);
FORCEPROP 2 LAST $XR0 133 
J 0
(-561 1375);
DISPLAY 0.638298 (-561 1375);
PAINT MONO (-561 1375);
FORCEPROP 1 LAST COMMENT_BODY TRUE
J 0
(-795 1280);
DISPLAY 0.872340 (-795 1280);
PAINT GREEN (-795 1280);
DISPLAY INVISIBLE (-795 1280);
FORCEPROP 1 LAST OFFPAGE TRUE
J 0
(-425 1250);
DISPLAY 0.872340 (-425 1250);
PAINT GREEN (-425 1250);
DISPLAY INVISIBLE (-425 1250);
FORCEPROP 2 LAST PATH I49
J 0
(-575 1450);
DISPLAY 1.021277 (-575 1450);
PAINT ORANGE (-575 1450);
DISPLAY INVISIBLE (-575 1450);
FORCEPROP 2 LAST CDS_LIB mstr_standard
J 0
(-750 1375);
PAINT ORANGE (-750 1375);
DISPLAY INVISIBLE (-750 1375);
FORCEADD OFFPAGE..4
R 2
(-7225 2450);
FORCEPROP 2 LAST $XR0 181 
J 0
(-7477 2450);
DISPLAY 0.638298 (-7477 2450);
PAINT MONO (-7477 2450);
FORCEPROP 1 LAST COMMENT_BODY TRUE
J 2
(-7200 2350);
DISPLAY 1.872340 (-7200 2350);
PAINT GREEN (-7200 2350);
DISPLAY INVISIBLE (-7200 2350);
FORCEPROP 1 LAST OFFPAGE TRUE
J 2
(-7550 2325);
PAINT GREEN (-7550 2325);
DISPLAY INVISIBLE (-7550 2325);
FORCEPROP 2 LAST PATH I50
J 0
(-7175 2525);
DISPLAY 1.021277 (-7175 2525);
PAINT ORANGE (-7175 2525);
DISPLAY INVISIBLE (-7175 2525);
FORCEPROP 2 LAST CDS_LIB mstr_standard
J 0
(-7225 2450);
PAINT ORANGE (-7225 2450);
DISPLAY INVISIBLE (-7225 2450);
FORCEADD AGND0..1
(-7025 1975);
FORCEPROP 3 LASTPIN (-7025 2025) SIG_NAME AGND_HSC\g
J 0
(-7015 2035);
DISPLAY 0.659574 (-7015 2035);
PAINT MONO (-7015 2035);
DISPLAY INVISIBLE (-7015 2035);
FORCEPROP 1 LAST HDL_POWER AGND_HSC
J 1
(-7025 1925);
DISPLAY 0.617021 (-7025 1925);
PAINT GREEN (-7025 1925);
FORCEPROP 1 LAST BODY_TYPE PLUMBING
J 0
(-7070 1932);
DISPLAY 0.340426 (-7070 1932);
PAINT GREEN (-7070 1932);
DISPLAY INVISIBLE (-7070 1932);
FORCEPROP 1 LAST VOLTAGE 0
J 0
(-7025 1975);
PAINT SKYBLUE (-7025 1975);
DISPLAY INVISIBLE (-7025 1975);
FORCEPROP 2 LAST BOM_COST MIO_VRD_MAIN
J 0
(-7000 1950);
PAINT ORANGE (-7000 1950);
DISPLAY INVISIBLE (-7000 1950);
FORCEPROP 2 LAST CDS_LIB mstr_symbols
J 0
(-7025 1975);
PAINT ORANGE (-7025 1975);
DISPLAY INVISIBLE (-7025 1975);
FORCEPROP 1 LAST PATH I52
J 0
(-6950 1975);
DISPLAY 0.872340 (-6950 1975);
PAINT AQUA (-6950 1975);
DISPLAY INVISIBLE (-6950 1975);
FORCEPROP 2 LAST ROOM VR_P3V3
J 0
(-7050 1950);
PAINT ORANGE (-7050 1950);
DISPLAY INVISIBLE (-7050 1950);
FORCEADD CAP_A..1
R 2
(-7025 2175);
FORCEPROP 1 LAST TOLERANCE 10%
J 2
(-7075 2125);
DISPLAY 0.617021 (-7075 2125);
PAINT SKYBLUE (-7075 2125);
FORCEPROP 1 LAST PART_NUMBER A36096-030
J 2
(-7075 2025);
DISPLAY 0.617021 (-7075 2025);
PAINT BLUE (-7075 2025);
FORCEPROP 1 LAST PACK_TYPE 0402V
J 2
(-7075 1975);
DISPLAY 0.617021 (-7075 1975);
PAINT SKYBLUE (-7075 1975);
FORCEPROP 1 LASTPIN (-7025 2075) $PN 2
J 2
(-7035 2055);
DISPLAY 0.617021 (-7035 2055);
PAINT ORANGE (-7035 2055);
FORCEPROP 1 LAST MATERIAL X7R
J 2
(-7075 2075);
DISPLAY 0.617021 (-7075 2075);
PAINT SKYBLUE (-7075 2075);
FORCEPROP 1 LASTPIN (-7025 2275) $PN 1
J 2
(-7035 2255);
DISPLAY 0.617021 (-7035 2255);
PAINT ORANGE (-7035 2255);
FORCEPROP 1 LAST VALUE 0.1UF
J 2
(-7075 2225);
DISPLAY 0.617021 (-7075 2225);
PAINT SKYBLUE (-7075 2225);
FORCEPROP 1 LAST VOLTAGE 16V
J 2
(-7075 2175);
DISPLAY 0.617021 (-7075 2175);
PAINT SKYBLUE (-7075 2175);
FORCEPROP 1 LAST LOCATION C1D11
J 2
(-7075 2275);
DISPLAY 0.617021 (-7075 2275);
PAINT AQUA (-7075 2275);
FORCEPROP 2 LAST SEC 1
J 0
(-7075 2375);
DISPLAY 0.680851 (-7075 2375);
PAINT MONO (-7075 2375);
DISPLAY INVISIBLE (-7075 2375);
FORCEPROP 2 LAST SEC_TYPE 0402V
J 0
(-7075 2375);
DISPLAY 1.021277 (-7075 2375);
PAINT ORANGE (-7075 2375);
DISPLAY INVISIBLE (-7075 2375);
FORCEPROP 2 LAST CDS_SEC 1
J 0
(-7075 2325);
PAINT ORANGE (-7075 2325);
DISPLAY INVISIBLE (-7075 2325);
FORCEPROP 1 LAST PATH I53
J 2
(-7075 2325);
DISPLAY 0.978723 (-7075 2325);
PAINT WHITE (-7075 2325);
DISPLAY INVISIBLE (-7075 2325);
FORCEPROP 0 LAST ROOM HOT_SWAP
J 0
(-7075 2325);
DISPLAY 1.021277 (-7075 2325);
PAINT ORANGE (-7075 2325);
DISPLAY INVISIBLE (-7075 2325);
FORCEPROP 2 LAST CDS_LIB dev_discrete
J 0
(-7025 2175);
PAINT ORANGE (-7025 2175);
DISPLAY INVISIBLE (-7025 2175);
FORCEPROP 2 LAST CDS_LOCATION C1D11
J 2
(-7075 2275);
DISPLAY 0.617021 (-7075 2275);
PAINT AQUA (-7075 2275);
DISPLAY INVISIBLE (-7075 2275);
FORCEADD RES..2
(-6725 2025);
FORCEPROP 1 LAST LOCATION R9P23
J 0
(-6680 2150);
DISPLAY 0.617021 (-6680 2150);
PAINT AQUA (-6680 2150);
FORCEPROP 1 LAST VALUE 100.0K
J 0
(-6680 2100);
DISPLAY 0.617021 (-6680 2100);
PAINT SKYBLUE (-6680 2100);
FORCEPROP 1 LAST WATTAGE 1/16W
J 0
(-6685 2000);
DISPLAY 0.617021 (-6685 2000);
PAINT SKYBLUE (-6685 2000);
FORCEPROP 1 LAST PART_NUMBER G21796-010
J 0
(-6685 1900);
DISPLAY 0.617021 (-6685 1900);
PAINT BLUE (-6685 1900);
FORCEPROP 1 LASTPIN (-6725 2125) $PN 1
J 0
(-6720 2087);
DISPLAY 0.617021 (-6720 2087);
PAINT ORANGE (-6720 2087);
FORCEPROP 1 LASTPIN (-6725 1925) $PN 2
J 0
(-6720 1935);
DISPLAY 0.617021 (-6720 1935);
PAINT ORANGE (-6720 1935);
FORCEPROP 1 LAST TOLERANCE 1%
J 0
(-6680 2050);
DISPLAY 0.617021 (-6680 2050);
PAINT SKYBLUE (-6680 2050);
FORCEPROP 1 LAST MATERIAL CHIP
J 0
(-6685 1950);
DISPLAY 0.617021 (-6685 1950);
PAINT SKYBLUE (-6685 1950);
FORCEPROP 1 LAST PACK_TYPE 0402
J 0
(-6685 1825);
DISPLAY 0.617021 (-6685 1825);
PAINT SKYBLUE (-6685 1825);
FORCEPROP 2 LAST SEC 1
J 0
(-6675 2250);
DISPLAY 0.680851 (-6675 2250);
PAINT MONO (-6675 2250);
DISPLAY INVISIBLE (-6675 2250);
FORCEPROP 2 LAST SEC_TYPE 0402
J 0
(-6675 2250);
DISPLAY 1.021277 (-6675 2250);
PAINT ORANGE (-6675 2250);
DISPLAY INVISIBLE (-6675 2250);
FORCEPROP 1 LAST PATH I54
J 0
(-6675 2200);
DISPLAY 0.978723 (-6675 2200);
PAINT WHITE (-6675 2200);
DISPLAY INVISIBLE (-6675 2200);
FORCEPROP 0 LAST ROOM HOT_SWAP
J 0
(-6675 2200);
DISPLAY 1.021277 (-6675 2200);
PAINT ORANGE (-6675 2200);
DISPLAY INVISIBLE (-6675 2200);
FORCEPROP 2 LAST CDS_LOCATION R9P23
J 0
(-6680 2150);
DISPLAY 0.617021 (-6680 2150);
PAINT AQUA (-6680 2150);
DISPLAY INVISIBLE (-6680 2150);
FORCEPROP 2 LAST CDS_LIB mstr_discrete
J 0
(-6725 2025);
PAINT ORANGE (-6725 2025);
DISPLAY INVISIBLE (-6725 2025);
FORCEADD RES..2
R 2
(-6725 1725);
FORCEPROP 1 LASTPIN (-6725 1625) $PN 2
J 2
(-6730 1635);
DISPLAY 0.617021 (-6730 1635);
PAINT ORANGE (-6730 1635);
FORCEPROP 1 LASTPIN (-6725 1825) $PN 1
J 2
(-6730 1787);
DISPLAY 0.617021 (-6730 1787);
PAINT ORANGE (-6730 1787);
FORCEPROP 1 LAST WATTAGE 1/16W
J 2
(-6765 1700);
DISPLAY 0.617021 (-6765 1700);
PAINT SKYBLUE (-6765 1700);
FORCEPROP 1 LAST VALUE 12.1K
J 2
(-6770 1800);
DISPLAY 0.617021 (-6770 1800);
PAINT SKYBLUE (-6770 1800);
FORCEPROP 1 LAST TOLERANCE 1%
J 2
(-6770 1750);
DISPLAY 0.617021 (-6770 1750);
PAINT SKYBLUE (-6770 1750);
FORCEPROP 1 LAST LOCATION R9P24
J 2
(-6770 1850);
DISPLAY 0.617021 (-6770 1850);
PAINT AQUA (-6770 1850);
FORCEPROP 1 LAST PACK_TYPE 0402
J 2
(-6765 1550);
DISPLAY 0.617021 (-6765 1550);
PAINT SKYBLUE (-6765 1550);
FORCEPROP 1 LAST PART_NUMBER G21796-089
J 2
(-6765 1600);
DISPLAY 0.617021 (-6765 1600);
PAINT BLUE (-6765 1600);
FORCEPROP 1 LAST MATERIAL CHIP
J 2
(-6765 1650);
DISPLAY 0.617021 (-6765 1650);
PAINT SKYBLUE (-6765 1650);
FORCEPROP 2 LAST SEC_TYPE 0402
J 0
(-6775 1950);
DISPLAY 1.021277 (-6775 1950);
PAINT ORANGE (-6775 1950);
DISPLAY INVISIBLE (-6775 1950);
FORCEPROP 2 LAST SEC 1
J 0
(-6775 1950);
DISPLAY 0.680851 (-6775 1950);
PAINT MONO (-6775 1950);
DISPLAY INVISIBLE (-6775 1950);
FORCEPROP 2 LAST BOM_COST MIO_USB
J 2
(-6775 1900);
PAINT MONO (-6775 1900);
DISPLAY INVISIBLE (-6775 1900);
FORCEPROP 1 LAST PATH I55
J 2
(-6775 1900);
DISPLAY 0.978723 (-6775 1900);
PAINT WHITE (-6775 1900);
DISPLAY INVISIBLE (-6775 1900);
FORCEPROP 2 LAST ROOM HOT_SWAP
J 2
(-6775 1900);
PAINT PEACH (-6775 1900);
DISPLAY INVISIBLE (-6775 1900);
FORCEPROP 2 LAST CDS_LOCATION R9P24
J 2
(-6770 1850);
DISPLAY 0.617021 (-6770 1850);
PAINT AQUA (-6770 1850);
DISPLAY INVISIBLE (-6770 1850);
FORCEPROP 2 LAST CDS_LIB mstr_discrete
J 0
(-6725 1725);
PAINT ORANGE (-6725 1725);
DISPLAY INVISIBLE (-6725 1725);
FORCEADD AGND0..1
(-6725 1525);
FORCEPROP 3 LASTPIN (-6725 1575) SIG_NAME AGND_HSC\g
J 0
(-6715 1585);
DISPLAY 0.659574 (-6715 1585);
PAINT MONO (-6715 1585);
DISPLAY INVISIBLE (-6715 1585);
FORCEPROP 1 LAST HDL_POWER AGND_HSC
J 1
(-6725 1475);
DISPLAY 0.617021 (-6725 1475);
PAINT GREEN (-6725 1475);
FORCEPROP 1 LAST BODY_TYPE PLUMBING
J 0
(-6770 1482);
DISPLAY 0.340426 (-6770 1482);
PAINT GREEN (-6770 1482);
DISPLAY INVISIBLE (-6770 1482);
FORCEPROP 1 LAST PATH I56
J 0
(-6650 1525);
DISPLAY 0.872340 (-6650 1525);
PAINT AQUA (-6650 1525);
DISPLAY INVISIBLE (-6650 1525);
FORCEPROP 1 LAST VOLTAGE 0
J 0
(-6725 1525);
PAINT SKYBLUE (-6725 1525);
DISPLAY INVISIBLE (-6725 1525);
FORCEPROP 2 LAST CDS_LIB mstr_symbols
J 0
(-6725 1525);
PAINT ORANGE (-6725 1525);
DISPLAY INVISIBLE (-6725 1525);
FORCEPROP 2 LAST BOM_COST MIO_VRD_MAIN
J 0
(-6700 1500);
PAINT ORANGE (-6700 1500);
DISPLAY INVISIBLE (-6700 1500);
FORCEPROP 2 LAST ROOM VR_P3V3
J 0
(-6750 1500);
PAINT ORANGE (-6750 1500);
DISPLAY INVISIBLE (-6750 1500);
FORCEADD NPN..1
(-525 1700);
FORCEPROP 1 LAST PACK_TYPE SM
J 0
(-375 1600);
DISPLAY 0.617021 (-375 1600);
PAINT SKYBLUE (-375 1600);
FORCEPROP 1 LASTPIN (-475 1800) $PN 3
J 0
(-456 1810);
DISPLAY 0.617021 (-456 1810);
PAINT GREEN (-456 1810);
FORCEPROP 1 LASTPIN (-625 1700) $PN 1
J 0
(-680 1725);
DISPLAY 0.617021 (-680 1725);
PAINT GREEN (-680 1725);
FORCEPROP 1 LASTPIN (-475 1600) $PN 2
J 0
(-450 1550);
DISPLAY 0.617021 (-450 1550);
PAINT GREEN (-450 1550);
FORCEPROP 1 LAST LOCATION Q1D3
J 0
(-375 1750);
DISPLAY 0.617021 (-375 1750);
PAINT AQUA (-375 1750);
FORCEPROP 1 LAST VALUE MMBT3904
J 0
(-375 1700);
DISPLAY 0.617021 (-375 1700);
PAINT SKYBLUE (-375 1700);
FORCEPROP 1 LAST MATERIAL IC
J 0
(-375 1650);
DISPLAY 0.617021 (-375 1650);
PAINT SKYBLUE (-375 1650);
FORCEPROP 1 LAST PART_NUMBER C52245-001
J 0
(-375 1550);
DISPLAY 0.617021 (-375 1550);
PAINT BLUE (-375 1550);
FORCEPROP 2 LAST SEC_TYPE SM
J 0
(-375 1850);
DISPLAY 1.021277 (-375 1850);
PAINT ORANGE (-375 1850);
DISPLAY INVISIBLE (-375 1850);
FORCEPROP 2 LAST SEC 1
J 0
(-375 1850);
DISPLAY 0.680851 (-375 1850);
PAINT MONO (-375 1850);
DISPLAY INVISIBLE (-375 1850);
FORCEPROP 2 LAST CDS_LOCATION Q1D3
J 0
(-375 1750);
DISPLAY 0.617021 (-375 1750);
PAINT AQUA (-375 1750);
DISPLAY INVISIBLE (-375 1750);
FORCEPROP 1 LAST PATH I58
J 0
(-375 1800);
DISPLAY 0.978723 (-375 1800);
PAINT BLUE (-375 1800);
DISPLAY INVISIBLE (-375 1800);
FORCEPROP 0 LAST ROOM HOT_SWAP
J 0
(-375 1850);
DISPLAY 1.021277 (-375 1850);
PAINT ORANGE (-375 1850);
DISPLAY INVISIBLE (-375 1850);
FORCEPROP 2 LAST CDS_LIB mstr_discrete
J 0
(-525 1700);
PAINT ORANGE (-525 1700);
DISPLAY INVISIBLE (-525 1700);
FORCEADD OFFPAGE..2
(-825 3950);
FORCEPROP 2 LAST $XR2 170 
J 0
(-396 3950);
DISPLAY 0.638298 (-396 3950);
PAINT MONO (-396 3950);
FORCEPROP 2 LAST $XR1 146 
J 0
(-516 3950);
DISPLAY 0.638298 (-516 3950);
PAINT MONO (-516 3950);
FORCEPROP 2 LAST $XR0 120 
J 0
(-636 3950);
DISPLAY 0.638298 (-636 3950);
PAINT MONO (-636 3950);
FORCEPROP 1 LAST COMMENT_BODY TRUE
J 0
(-870 3855);
DISPLAY 0.872340 (-870 3855);
PAINT GREEN (-870 3855);
DISPLAY INVISIBLE (-870 3855);
FORCEPROP 1 LAST OFFPAGE TRUE
J 0
(-500 3825);
DISPLAY 0.872340 (-500 3825);
PAINT GREEN (-500 3825);
DISPLAY INVISIBLE (-500 3825);
FORCEPROP 2 LAST PATH I63
J 0
(-650 4025);
DISPLAY 1.021277 (-650 4025);
PAINT ORANGE (-650 4025);
DISPLAY INVISIBLE (-650 4025);
FORCEPROP 2 LAST CDS_LIB mstr_standard
J 0
(-825 3950);
PAINT ORANGE (-825 3950);
DISPLAY INVISIBLE (-825 3950);
FORCEADD OFFPAGE..2
(-825 2925);
FORCEPROP 2 LAST $XR0 200 
J 0
(-636 2925);
DISPLAY 0.638298 (-636 2925);
PAINT MONO (-636 2925);
FORCEPROP 1 LAST COMMENT_BODY TRUE
J 0
(-870 2830);
DISPLAY 0.872340 (-870 2830);
PAINT GREEN (-870 2830);
DISPLAY INVISIBLE (-870 2830);
FORCEPROP 1 LAST OFFPAGE TRUE
J 0
(-500 2800);
DISPLAY 0.872340 (-500 2800);
PAINT GREEN (-500 2800);
DISPLAY INVISIBLE (-500 2800);
FORCEPROP 2 LAST PATH I64
J 0
(-650 3000);
DISPLAY 1.021277 (-650 3000);
PAINT ORANGE (-650 3000);
DISPLAY INVISIBLE (-650 3000);
FORCEPROP 2 LAST CDS_LIB mstr_standard
J 0
(-825 2925);
PAINT ORANGE (-825 2925);
DISPLAY INVISIBLE (-825 2925);
FORCEADD RES..2
(-400 3025);
FORCEPROP 1 LAST LOCATION R1D36
J 0
(-355 3150);
DISPLAY 0.617021 (-355 3150);
PAINT AQUA (-355 3150);
FORCEPROP 1 LASTPIN (-400 3125) $PN 1
J 0
(-395 3087);
DISPLAY 0.617021 (-395 3087);
PAINT ORANGE (-395 3087);
FORCEPROP 1 LASTPIN (-400 2925) $PN 2
J 0
(-395 2935);
DISPLAY 0.617021 (-395 2935);
PAINT ORANGE (-395 2935);
FORCEPROP 1 LAST VALUE 1.00K
J 0
(-355 3100);
DISPLAY 0.617021 (-355 3100);
PAINT SKYBLUE (-355 3100);
FORCEPROP 1 LAST TOLERANCE 1%
J 0
(-355 3050);
DISPLAY 0.617021 (-355 3050);
PAINT SKYBLUE (-355 3050);
FORCEPROP 1 LAST WATTAGE 1/16W
J 0
(-360 3000);
DISPLAY 0.617021 (-360 3000);
PAINT SKYBLUE (-360 3000);
FORCEPROP 1 LAST MATERIAL CHIP
J 0
(-360 2950);
DISPLAY 0.617021 (-360 2950);
PAINT SKYBLUE (-360 2950);
FORCEPROP 1 LAST PART_NUMBER G21796-026
J 0
(-360 2900);
DISPLAY 0.617021 (-360 2900);
PAINT BLUE (-360 2900);
FORCEPROP 1 LAST PACK_TYPE 0402
J 0
(-360 2850);
DISPLAY 0.617021 (-360 2850);
PAINT SKYBLUE (-360 2850);
FORCEPROP 2 LAST SEC_TYPE 0402
J 0
(-350 3250);
DISPLAY 1.021277 (-350 3250);
PAINT ORANGE (-350 3250);
DISPLAY INVISIBLE (-350 3250);
FORCEPROP 2 LAST BOM_COST MIO_USB
J 0
(-350 3200);
PAINT MONO (-350 3200);
DISPLAY INVISIBLE (-350 3200);
FORCEPROP 2 LAST CDS_LOCATION R1D36
J 0
(-355 3150);
DISPLAY 0.617021 (-355 3150);
PAINT AQUA (-355 3150);
DISPLAY INVISIBLE (-355 3150);
FORCEPROP 2 LAST SEC 1
J 0
(-350 3250);
DISPLAY 0.680851 (-350 3250);
PAINT MONO (-350 3250);
DISPLAY INVISIBLE (-350 3250);
FORCEPROP 2 LAST ROOM HOT_SWAP
J 0
(-350 3200);
PAINT PEACH (-350 3200);
DISPLAY INVISIBLE (-350 3200);
FORCEPROP 1 LAST PATH I65
J 0
(-350 3200);
DISPLAY 0.978723 (-350 3200);
PAINT WHITE (-350 3200);
DISPLAY INVISIBLE (-350 3200);
FORCEPROP 2 LAST CDS_LIB mstr_discrete
J 2
(-400 3025);
PAINT ORANGE (-400 3025);
DISPLAY INVISIBLE (-400 3025);
FORCEADD CAP_A..1
(-400 2625);
FORCEPROP 1 LAST VOLTAGE 16V
J 0
(-350 2625);
DISPLAY 0.617021 (-350 2625);
PAINT SKYBLUE (-350 2625);
FORCEPROP 1 LASTPIN (-400 2725) $PN 1
J 0
(-390 2705);
DISPLAY 0.617021 (-390 2705);
PAINT ORANGE (-390 2705);
FORCEPROP 1 LASTPIN (-400 2525) $PN 2
J 0
(-390 2505);
DISPLAY 0.617021 (-390 2505);
PAINT ORANGE (-390 2505);
FORCEPROP 1 LAST LOCATION C9P12
J 0
(-350 2725);
DISPLAY 0.617021 (-350 2725);
PAINT AQUA (-350 2725);
FORCEPROP 1 LAST VALUE 0.1UF
J 0
(-350 2675);
DISPLAY 0.617021 (-350 2675);
PAINT SKYBLUE (-350 2675);
FORCEPROP 1 LAST TOLERANCE 10%
J 0
(-350 2575);
DISPLAY 0.617021 (-350 2575);
PAINT SKYBLUE (-350 2575);
FORCEPROP 1 LAST MATERIAL EMPTY
J 0
(-350 2525);
DISPLAY 0.617021 (-350 2525);
PAINT RED (-350 2525);
FORCEPROP 1 LAST PART_NUMBER A36096-030
J 0
(-350 2475);
DISPLAY 0.617021 (-350 2475);
PAINT BLUE (-350 2475);
FORCEPROP 1 LAST PACK_TYPE 0402V
J 0
(-350 2425);
DISPLAY 0.617021 (-350 2425);
PAINT SKYBLUE (-350 2425);
FORCEPROP 2 LAST SEC_TYPE 0402V
J 0
(-350 2825);
DISPLAY 1.021277 (-350 2825);
PAINT ORANGE (-350 2825);
DISPLAY INVISIBLE (-350 2825);
FORCEPROP 2 LAST SEC 1
J 0
(-350 2825);
DISPLAY 0.680851 (-350 2825);
PAINT MONO (-350 2825);
DISPLAY INVISIBLE (-350 2825);
FORCEPROP 0 LAST ROOM HOT_SWAP
J 2
(-350 2775);
DISPLAY 1.021277 (-350 2775);
PAINT ORANGE (-350 2775);
DISPLAY INVISIBLE (-350 2775);
FORCEPROP 2 LAST CDS_LOCATION C9P12
J 0
(-350 2725);
DISPLAY 0.617021 (-350 2725);
PAINT AQUA (-350 2725);
DISPLAY INVISIBLE (-350 2725);
FORCEPROP 1 LAST PATH I67
J 0
(-350 2775);
DISPLAY 0.978723 (-350 2775);
PAINT WHITE (-350 2775);
DISPLAY INVISIBLE (-350 2775);
FORCEPROP 2 LAST CDS_LIB dev_discrete
J 0
(-400 2625);
PAINT ORANGE (-400 2625);
DISPLAY INVISIBLE (-400 2625);
FORCEADD AGND0..1
(-400 2400);
FORCEPROP 3 LASTPIN (-400 2450) SIG_NAME AGND_HSC\g
J 0
(-390 2460);
DISPLAY 0.659574 (-390 2460);
PAINT MONO (-390 2460);
DISPLAY INVISIBLE (-390 2460);
FORCEPROP 1 LAST HDL_POWER AGND_HSC
J 1
(-400 2350);
DISPLAY 0.617021 (-400 2350);
PAINT GREEN (-400 2350);
FORCEPROP 1 LAST BODY_TYPE PLUMBING
J 0
(-445 2357);
DISPLAY 0.340426 (-445 2357);
PAINT GREEN (-445 2357);
DISPLAY INVISIBLE (-445 2357);
FORCEPROP 2 LAST BOM_COST MIO_VRD_MAIN
J 0
(-375 2375);
PAINT ORANGE (-375 2375);
DISPLAY INVISIBLE (-375 2375);
FORCEPROP 1 LAST PATH I68
J 0
(-325 2400);
DISPLAY 0.872340 (-325 2400);
PAINT AQUA (-325 2400);
DISPLAY INVISIBLE (-325 2400);
FORCEPROP 1 LAST VOLTAGE 0
J 0
(-400 2400);
PAINT SKYBLUE (-400 2400);
DISPLAY INVISIBLE (-400 2400);
FORCEPROP 2 LAST CDS_LIB mstr_symbols
J 0
(-400 2400);
PAINT ORANGE (-400 2400);
DISPLAY INVISIBLE (-400 2400);
FORCEPROP 2 LAST ROOM VR_P3V3
J 0
(-425 2375);
PAINT ORANGE (-425 2375);
DISPLAY INVISIBLE (-425 2375);
FORCEADD OFFPAGE..2
(-825 2725);
FORCEPROP 2 LAST $XR0 200 
J 0
(-636 2725);
DISPLAY 0.638298 (-636 2725);
PAINT MONO (-636 2725);
FORCEPROP 1 LAST COMMENT_BODY TRUE
J 0
(-870 2630);
DISPLAY 0.872340 (-870 2630);
PAINT GREEN (-870 2630);
DISPLAY INVISIBLE (-870 2630);
FORCEPROP 1 LAST OFFPAGE TRUE
J 0
(-500 2600);
DISPLAY 0.872340 (-500 2600);
PAINT GREEN (-500 2600);
DISPLAY INVISIBLE (-500 2600);
FORCEPROP 2 LAST PATH I69
J 0
(-650 2800);
DISPLAY 1.021277 (-650 2800);
PAINT ORANGE (-650 2800);
DISPLAY INVISIBLE (-650 2800);
FORCEPROP 2 LAST CDS_LIB mstr_standard
J 0
(-825 2725);
PAINT ORANGE (-825 2725);
DISPLAY INVISIBLE (-825 2725);
FORCEADD CAP_A..1
R 2
(-6775 3575);
FORCEPROP 1 LAST PART_NUMBER A36096-030
J 2
(-6825 3425);
DISPLAY 0.617021 (-6825 3425);
PAINT BLUE (-6825 3425);
FORCEPROP 1 LAST LOCATION C1D27
J 2
(-6825 3675);
DISPLAY 0.617021 (-6825 3675);
PAINT AQUA (-6825 3675);
FORCEPROP 1 LAST VALUE 0.1UF
J 2
(-6825 3625);
DISPLAY 0.617021 (-6825 3625);
PAINT SKYBLUE (-6825 3625);
FORCEPROP 1 LAST PACK_TYPE 0402V
J 2
(-6825 3375);
DISPLAY 0.617021 (-6825 3375);
PAINT SKYBLUE (-6825 3375);
FORCEPROP 1 LAST VOLTAGE 16V
J 2
(-6825 3575);
DISPLAY 0.617021 (-6825 3575);
PAINT SKYBLUE (-6825 3575);
FORCEPROP 1 LAST TOLERANCE 10%
J 2
(-6825 3525);
DISPLAY 0.617021 (-6825 3525);
PAINT SKYBLUE (-6825 3525);
FORCEPROP 1 LAST MATERIAL X7R
J 2
(-6825 3475);
DISPLAY 0.617021 (-6825 3475);
PAINT SKYBLUE (-6825 3475);
FORCEPROP 1 LASTPIN (-6775 3475) $PN 2
J 2
(-6785 3455);
DISPLAY 0.617021 (-6785 3455);
PAINT ORANGE (-6785 3455);
FORCEPROP 1 LASTPIN (-6775 3675) $PN 1
J 2
(-6785 3655);
DISPLAY 0.617021 (-6785 3655);
PAINT ORANGE (-6785 3655);
FORCEPROP 2 LAST CDS_LOCATION C1D27
J 2
(-6825 3675);
DISPLAY 0.617021 (-6825 3675);
PAINT AQUA (-6825 3675);
DISPLAY INVISIBLE (-6825 3675);
FORCEPROP 0 LAST ROOM HOT_SWAP
J 0
(-6825 3725);
DISPLAY 1.021277 (-6825 3725);
PAINT ORANGE (-6825 3725);
DISPLAY INVISIBLE (-6825 3725);
FORCEPROP 1 LAST PATH I7
J 2
(-6825 3725);
DISPLAY 0.978723 (-6825 3725);
PAINT WHITE (-6825 3725);
DISPLAY INVISIBLE (-6825 3725);
FORCEPROP 2 LAST CDS_SEC 1
J 0
(-6825 3725);
PAINT ORANGE (-6825 3725);
DISPLAY INVISIBLE (-6825 3725);
FORCEPROP 2 LAST SEC_TYPE 0402V
J 0
(-6825 3775);
DISPLAY 1.021277 (-6825 3775);
PAINT ORANGE (-6825 3775);
DISPLAY INVISIBLE (-6825 3775);
FORCEPROP 2 LAST SEC 1
J 0
(-6825 3775);
DISPLAY 0.680851 (-6825 3775);
PAINT MONO (-6825 3775);
DISPLAY INVISIBLE (-6825 3775);
FORCEPROP 2 LAST CDS_LIB dev_discrete
J 0
(-6775 3575);
PAINT ORANGE (-6775 3575);
DISPLAY INVISIBLE (-6775 3575);
FORCEADD OFFPAGE..2
(-775 2075);
FORCEPROP 2 LAST $XR0 200 
J 0
(-586 2075);
DISPLAY 0.638298 (-586 2075);
PAINT MONO (-586 2075);
FORCEPROP 1 LAST COMMENT_BODY TRUE
J 0
(-820 1980);
DISPLAY 0.872340 (-820 1980);
PAINT GREEN (-820 1980);
DISPLAY INVISIBLE (-820 1980);
FORCEPROP 1 LAST OFFPAGE TRUE
J 0
(-450 1950);
DISPLAY 0.872340 (-450 1950);
PAINT GREEN (-450 1950);
DISPLAY INVISIBLE (-450 1950);
FORCEPROP 2 LAST PATH I71
J 0
(-600 2150);
DISPLAY 1.021277 (-600 2150);
PAINT ORANGE (-600 2150);
DISPLAY INVISIBLE (-600 2150);
FORCEPROP 2 LAST CDS_LIB mstr_standard
J 0
(-775 2075);
PAINT ORANGE (-775 2075);
DISPLAY INVISIBLE (-775 2075);
FORCEADD OFFPAGE..2
(-775 2025);
FORCEPROP 2 LAST $XR0 200 
J 0
(-586 2025);
DISPLAY 0.638298 (-586 2025);
PAINT MONO (-586 2025);
FORCEPROP 1 LAST COMMENT_BODY TRUE
J 0
(-820 1930);
DISPLAY 0.872340 (-820 1930);
PAINT GREEN (-820 1930);
DISPLAY INVISIBLE (-820 1930);
FORCEPROP 1 LAST OFFPAGE TRUE
J 0
(-450 1900);
DISPLAY 0.872340 (-450 1900);
PAINT GREEN (-450 1900);
DISPLAY INVISIBLE (-450 1900);
FORCEPROP 2 LAST PATH I72
J 0
(-600 2100);
DISPLAY 1.021277 (-600 2100);
PAINT ORANGE (-600 2100);
DISPLAY INVISIBLE (-600 2100);
FORCEPROP 2 LAST CDS_LIB mstr_standard
J 0
(-775 2025);
PAINT ORANGE (-775 2025);
DISPLAY INVISIBLE (-775 2025);
FORCEADD OFFPAGE..2
(-775 1975);
FORCEPROP 2 LAST $XR0 200 
J 0
(-586 1975);
DISPLAY 0.638298 (-586 1975);
PAINT MONO (-586 1975);
FORCEPROP 1 LAST COMMENT_BODY TRUE
J 0
(-820 1880);
DISPLAY 0.702128 (-820 1880);
PAINT GREEN (-820 1880);
DISPLAY INVISIBLE (-820 1880);
FORCEPROP 1 LAST OFFPAGE TRUE
J 0
(-450 1850);
DISPLAY 0.872340 (-450 1850);
PAINT GREEN (-450 1850);
DISPLAY INVISIBLE (-450 1850);
FORCEPROP 2 LAST PATH I73
J 0
(-600 2050);
DISPLAY 1.021277 (-600 2050);
PAINT ORANGE (-600 2050);
DISPLAY INVISIBLE (-600 2050);
FORCEPROP 2 LAST CDS_LIB mstr_standard
J 0
(-775 1975);
PAINT ORANGE (-775 1975);
DISPLAY INVISIBLE (-775 1975);
FORCEADD OFFPAGE..2
(-775 1925);
FORCEPROP 2 LAST $XR0 200 
J 0
(-586 1925);
DISPLAY 0.638298 (-586 1925);
PAINT MONO (-586 1925);
FORCEPROP 1 LAST COMMENT_BODY TRUE
J 0
(-820 1830);
DISPLAY 0.872340 (-820 1830);
PAINT GREEN (-820 1830);
DISPLAY INVISIBLE (-820 1830);
FORCEPROP 1 LAST OFFPAGE TRUE
J 0
(-450 1800);
DISPLAY 0.872340 (-450 1800);
PAINT GREEN (-450 1800);
DISPLAY INVISIBLE (-450 1800);
FORCEPROP 2 LAST PATH I74
J 0
(-600 2000);
DISPLAY 1.021277 (-600 2000);
PAINT ORANGE (-600 2000);
DISPLAY INVISIBLE (-600 2000);
FORCEPROP 2 LAST CDS_LIB mstr_standard
J 0
(-775 1925);
PAINT ORANGE (-775 1925);
DISPLAY INVISIBLE (-775 1925);
FORCEADD P12V_STBY..1
(-400 3600);
FORCEPROP 3 LASTPIN (-400 3550) SIG_NAME P12V_STBY\g
J 0
(-390 3560);
DISPLAY 0.659574 (-390 3560);
PAINT MONO (-390 3560);
DISPLAY INVISIBLE (-390 3560);
FORCEPROP 1 LAST HDL_POWER P12V_STBY
J 0
(-700 3475);
DISPLAY 0.872340 (-700 3475);
PAINT ORANGE (-700 3475);
DISPLAY INVISIBLE (-700 3475);
FORCEPROP 1 LAST BODY_TYPE PLUMBING
J 0
(-445 3557);
DISPLAY 0.340426 (-445 3557);
PAINT GREEN (-445 3557);
DISPLAY INVISIBLE (-445 3557);
FORCEPROP 1 LAST PATH I75
J 0
(-355 3602);
DISPLAY 0.340426 (-355 3602);
PAINT GREEN (-355 3602);
DISPLAY INVISIBLE (-355 3602);
FORCEPROP 1 LAST SIZE 1B
J 0
(-355 3622);
DISPLAY 0.340426 (-355 3622);
PAINT GREEN (-355 3622);
DISPLAY INVISIBLE (-355 3622);
FORCEPROP 2 LAST CDS_LIB mstr_symbols
J 0
(-400 3600);
PAINT ORANGE (-400 3600);
DISPLAY INVISIBLE (-400 3600);
FORCEPROP 1 LAST VOLTAGE 12.0V
J 0
(-445 3557);
DISPLAY 0.340426 (-445 3557);
PAINT SKYBLUE (-445 3557);
DISPLAY INVISIBLE (-445 3557);
FORCEADD P12V_STBY..1
(-6725 2250);
FORCEPROP 3 LASTPIN (-6725 2200) SIG_NAME P12V_STBY\g
J 0
(-6715 2210);
DISPLAY 0.659574 (-6715 2210);
PAINT MONO (-6715 2210);
DISPLAY INVISIBLE (-6715 2210);
FORCEPROP 1 LAST HDL_POWER P12V_STBY
J 0
(-7025 2125);
DISPLAY 0.872340 (-7025 2125);
PAINT ORANGE (-7025 2125);
DISPLAY INVISIBLE (-7025 2125);
FORCEPROP 1 LAST BODY_TYPE PLUMBING
J 0
(-6770 2207);
DISPLAY 0.340426 (-6770 2207);
PAINT GREEN (-6770 2207);
DISPLAY INVISIBLE (-6770 2207);
FORCEPROP 1 LAST PATH I76
J 0
(-6680 2252);
DISPLAY 0.340426 (-6680 2252);
PAINT GREEN (-6680 2252);
DISPLAY INVISIBLE (-6680 2252);
FORCEPROP 2 LAST CDS_LIB mstr_symbols
J 0
(-6725 2250);
PAINT ORANGE (-6725 2250);
DISPLAY INVISIBLE (-6725 2250);
FORCEPROP 1 LAST SIZE 1B
J 0
(-6680 2272);
DISPLAY 0.340426 (-6680 2272);
PAINT GREEN (-6680 2272);
DISPLAY INVISIBLE (-6680 2272);
FORCEPROP 1 LAST VOLTAGE 12.0V
J 0
(-6770 2207);
DISPLAY 0.340426 (-6770 2207);
PAINT SKYBLUE (-6770 2207);
DISPLAY INVISIBLE (-6770 2207);
FORCEADD P12V_STBY..1
(-3125 1275);
FORCEPROP 3 LASTPIN (-3125 1225) SIG_NAME P12V_STBY\g
J 0
(-3115 1235);
DISPLAY 0.659574 (-3115 1235);
PAINT MONO (-3115 1235);
DISPLAY INVISIBLE (-3115 1235);
FORCEPROP 1 LAST HDL_POWER P12V_STBY
J 0
(-3425 1150);
DISPLAY 0.872340 (-3425 1150);
PAINT ORANGE (-3425 1150);
DISPLAY INVISIBLE (-3425 1150);
FORCEPROP 1 LAST BODY_TYPE PLUMBING
J 0
(-3170 1232);
DISPLAY 0.340426 (-3170 1232);
PAINT GREEN (-3170 1232);
DISPLAY INVISIBLE (-3170 1232);
FORCEPROP 1 LAST SIZE 1B
J 0
(-3080 1297);
DISPLAY 0.340426 (-3080 1297);
PAINT GREEN (-3080 1297);
DISPLAY INVISIBLE (-3080 1297);
FORCEPROP 2 LAST CDS_LIB mstr_symbols
J 0
(-3125 1275);
PAINT ORANGE (-3125 1275);
DISPLAY INVISIBLE (-3125 1275);
FORCEPROP 1 LAST PATH I77
J 0
(-3080 1277);
DISPLAY 0.340426 (-3080 1277);
PAINT GREEN (-3080 1277);
DISPLAY INVISIBLE (-3080 1277);
FORCEPROP 1 LAST VOLTAGE 12.0V
J 0
(-3170 1232);
DISPLAY 0.340426 (-3170 1232);
PAINT SKYBLUE (-3170 1232);
DISPLAY INVISIBLE (-3170 1232);
FORCEADD P12V_PSU..1
(-6675 4425);
FORCEPROP 3 LASTPIN (-6675 4375) SIG_NAME P12V_PSU\g
J 0
(-6665 4385);
DISPLAY 0.659574 (-6665 4385);
PAINT MONO (-6665 4385);
DISPLAY INVISIBLE (-6665 4385);
FORCEPROP 1 LAST HDL_POWER P12V_PSU
J 1
(-6675 4475);
DISPLAY 0.872340 (-6675 4475);
PAINT GREEN (-6675 4475);
DISPLAY INVISIBLE (-6675 4475);
FORCEPROP 1 LAST BODY_TYPE PLUMBING
J 0
(-6720 4382);
DISPLAY 0.340426 (-6720 4382);
PAINT GREEN (-6720 4382);
DISPLAY INVISIBLE (-6720 4382);
FORCEPROP 1 LAST PATH I79
J 0
(-6625 4450);
DISPLAY 0.872340 (-6625 4450);
PAINT AQUA (-6625 4450);
DISPLAY INVISIBLE (-6625 4450);
FORCEPROP 2 LAST ROOM P2V5_LAN_AUX_VR
J 0
(-6675 4525);
DISPLAY 0.617021 (-6675 4525);
PAINT ORANGE (-6675 4525);
DISPLAY INVISIBLE (-6675 4525);
FORCEPROP 2 LAST CDS_LIB mstr_symbols
J 0
(-6675 4425);
PAINT ORANGE (-6675 4425);
DISPLAY INVISIBLE (-6675 4425);
FORCEPROP 2 LAST BOM_COST NT_BASE_VRD
J 0
(-6675 4525);
DISPLAY 0.617021 (-6675 4525);
PAINT ORANGE (-6675 4525);
DISPLAY INVISIBLE (-6675 4525);
FORCEPROP 1 LAST VOLTAGE 12.0
J 0
(-6720 4382);
DISPLAY 0.340426 (-6720 4382);
PAINT SKYBLUE (-6720 4382);
DISPLAY INVISIBLE (-6720 4382);
FORCEADD FET_N_DUAL..5
(-6600 400);
FORCEPROP 1 LASTPIN (-6600 200) $PN 4
J 2
(-6517 225);
DISPLAY 0.617021 (-6517 225);
PAINT WHITE (-6517 225);
FORCEPROP 1 LASTPIN (-6800 300) $PN 5
J 2
(-6797 315);
DISPLAY 0.617021 (-6797 315);
PAINT WHITE (-6797 315);
FORCEPROP 1 LAST VALUE 2N7002DW
J 0
(-6400 350);
DISPLAY 0.617021 (-6400 350);
PAINT SKYBLUE (-6400 350);
FORCEPROP 1 LAST MATERIAL FET
J 0
(-6400 300);
DISPLAY 0.617021 (-6400 300);
PAINT SKYBLUE (-6400 300);
FORCEPROP 1 LAST PART_NUMBER D24280-001
J 0
(-6450 250);
DISPLAY 0.617021 (-6450 250);
PAINT BLUE (-6450 250);
FORCEPROP 1 LAST LOCATION Q1D1
J 0
(-6400 400);
DISPLAY 0.617021 (-6400 400);
PAINT AQUA (-6400 400);
FORCEPROP 1 LASTPIN (-6600 600) $PN 3
J 2
(-6547 565);
DISPLAY 0.617021 (-6547 565);
PAINT WHITE (-6547 565);
FORCEPROP 2 LAST ROOM HOT_SWAP
J 0
(-6450 550);
PAINT MONO (-6450 550);
DISPLAY INVISIBLE (-6450 550);
FORCEPROP 2 LAST SEC_TYPE SMLF
J 0
(-6400 500);
DISPLAY 1.021277 (-6400 500);
PAINT ORANGE (-6400 500);
DISPLAY INVISIBLE (-6400 500);
FORCEPROP 2 LAST SEC 2
J 0
(-6400 500);
DISPLAY 0.680851 (-6400 500);
PAINT MONO (-6400 500);
DISPLAY INVISIBLE (-6400 500);
FORCEPROP 1 LAST PACK_TYPE SMLF
J 0
(-6400 250);
DISPLAY 0.978723 (-6400 250);
PAINT SKYBLUE (-6400 250);
DISPLAY INVISIBLE (-6400 250);
FORCEPROP 2 LAST CDS_LOCATION Q1D1
J 0
(-6400 400);
DISPLAY 0.617021 (-6400 400);
PAINT AQUA (-6400 400);
DISPLAY INVISIBLE (-6400 400);
FORCEPROP 1 LAST PATH I82
J 0
(-6400 450);
DISPLAY 0.978723 (-6400 450);
PAINT BLUE (-6400 450);
DISPLAY INVISIBLE (-6400 450);
FORCEPROP 2 LAST CDS_LIB mstr_discrete
J 0
(-6600 400);
PAINT ORANGE (-6600 400);
DISPLAY INVISIBLE (-6600 400);
FORCEADD AGND0..1
(-5875 -25);
FORCEPROP 3 LASTPIN (-5875 25) SIG_NAME AGND_HSC\g
J 0
(-5865 35);
DISPLAY 0.659574 (-5865 35);
PAINT MONO (-5865 35);
DISPLAY INVISIBLE (-5865 35);
FORCEPROP 1 LAST HDL_POWER AGND_HSC
J 1
(-5875 -75);
DISPLAY 0.617021 (-5875 -75);
PAINT GREEN (-5875 -75);
FORCEPROP 1 LAST BODY_TYPE PLUMBING
J 0
(-5920 -68);
DISPLAY 0.340426 (-5920 -68);
PAINT GREEN (-5920 -68);
DISPLAY INVISIBLE (-5920 -68);
FORCEPROP 1 LAST VOLTAGE 0
J 0
(-5875 -25);
PAINT SKYBLUE (-5875 -25);
DISPLAY INVISIBLE (-5875 -25);
FORCEPROP 2 LAST CDS_LIB mstr_symbols
J 0
(-5875 -25);
PAINT ORANGE (-5875 -25);
DISPLAY INVISIBLE (-5875 -25);
FORCEPROP 1 LAST PATH I83
J 0
(-5800 -25);
DISPLAY 0.872340 (-5800 -25);
PAINT AQUA (-5800 -25);
DISPLAY INVISIBLE (-5800 -25);
FORCEPROP 2 LAST BOM_COST MIO_VRD_MAIN
J 0
(-5850 -50);
PAINT ORANGE (-5850 -50);
DISPLAY INVISIBLE (-5850 -50);
FORCEPROP 2 LAST ROOM VR_P3V3
J 0
(-5900 -50);
PAINT ORANGE (-5900 -50);
DISPLAY INVISIBLE (-5900 -50);
FORCEADD RES..1
R 1
(-6600 975);
FORCEPROP 0 LAST BOM_DS 64.68125.6DL
J 0
(-6600 1100);
DISPLAY 0.638298 (-6600 1100);
PAINT BROWN (-6600 1100);
DISPLAY BOTH (-6600 1100);
FORCEPROP 1 LAST TOLERANCE 1%
R 1
J 0
(-6525 950);
DISPLAY 0.617021 (-6525 950);
PAINT SKYBLUE (-6525 950);
FORCEPROP 1 LASTPIN (-6600 875) $PN 1
R 1
J 0
(-6562 912);
DISPLAY 0.617021 (-6562 912);
PAINT ORANGE (-6562 912);
FORCEPROP 1 LAST VALUE 90.9K
R 1
J 2
(-6550 900);
DISPLAY 0.617021 (-6550 900);
PAINT SKYBLUE (-6550 900);
FORCEPROP 1 LAST PART_NUMBER G21796-058
R 1
J 0
(-6650 800);
DISPLAY 0.617021 (-6650 800);
PAINT BLUE (-6650 800);
FORCEPROP 1 LAST LOCATION R1D13
R 1
J 0
(-6700 820);
DISPLAY 0.617021 (-6700 820);
PAINT AQUA (-6700 820);
FORCEPROP 1 LASTPIN (-6600 1075) $PN 2
R 1
J 0
(-6562 1037);
DISPLAY 0.617021 (-6562 1037);
PAINT ORANGE (-6562 1037);
FORCEPROP 1 LAST WATTAGE 1/16W
R 1
J 2
(-6475 925);
DISPLAY 0.617021 (-6475 925);
PAINT SKYBLUE (-6475 925);
FORCEPROP 1 LAST PACK_TYPE 0402
R 1
J 0
(-6400 775);
DISPLAY 0.617021 (-6400 775);
PAINT SKYBLUE (-6400 775);
FORCEPROP 1 LAST MATERIAL CHIP
R 1
J 0
(-6450 950);
DISPLAY 0.617021 (-6450 950);
PAINT SKYBLUE (-6450 950);
FORCEPROP 2 LAST ROOM HOT_SWAP
R 1
J 0
(-6775 1025);
PAINT MONO (-6775 1025);
DISPLAY INVISIBLE (-6775 1025);
FORCEPROP 1 LAST PATH I84
R 1
J 0
(-6750 925);
DISPLAY 0.978723 (-6750 925);
PAINT WHITE (-6750 925);
DISPLAY INVISIBLE (-6750 925);
FORCEPROP 2 LAST CDS_LIB mstr_discrete
R 1
J 0
(-6600 975);
PAINT ORANGE (-6600 975);
DISPLAY INVISIBLE (-6600 975);
FORCEPROP 2 LAST CDS_LOCATION R1D13
J 0
(-6800 1070);
DISPLAY 0.617021 (-6800 1070);
PAINT AQUA (-6800 1070);
DISPLAY INVISIBLE (-6800 1070);
FORCEPROP 2 LAST SEC_TYPE 0402
J 0
(-6775 1150);
DISPLAY 1.021277 (-6775 1150);
PAINT ORANGE (-6775 1150);
DISPLAY INVISIBLE (-6775 1150);
FORCEPROP 2 LAST SEC 1
J 0
(-6775 1150);
DISPLAY 0.680851 (-6775 1150);
PAINT MONO (-6775 1150);
DISPLAY INVISIBLE (-6775 1150);
FORCEPROP 0 LAST NO_XNET_CONNECTION 1
J 0
(-6800 1100);
PAINT MONO (-6800 1100);
DISPLAY INVISIBLE (-6800 1100);
FORCEADD RES..2
(-5875 875);
FORCEPROP 0 LAST BOM_DS 64.57625.6DL
J 0
(-5875 1100);
DISPLAY 0.638298 (-5875 1100);
PAINT BROWN (-5875 1100);
DISPLAY BOTH (-5875 1100);
FORCEPROP 1 LAST TOLERANCE 1%
J 0
(-5830 900);
DISPLAY 0.617021 (-5830 900);
PAINT SKYBLUE (-5830 900);
FORCEPROP 1 LAST VALUE 69.8K
J 0
(-5830 950);
DISPLAY 0.617021 (-5830 950);
PAINT SKYBLUE (-5830 950);
FORCEPROP 1 LAST LOCATION R1D16
J 0
(-5830 1000);
DISPLAY 0.617021 (-5830 1000);
PAINT AQUA (-5830 1000);
FORCEPROP 1 LASTPIN (-5875 775) $PN 2
J 0
(-5870 785);
DISPLAY 0.617021 (-5870 785);
PAINT ORANGE (-5870 785);
FORCEPROP 1 LASTPIN (-5875 975) $PN 1
J 0
(-5870 937);
DISPLAY 0.617021 (-5870 937);
PAINT ORANGE (-5870 937);
FORCEPROP 1 LAST PACK_TYPE 0402
J 0
(-5835 700);
DISPLAY 0.617021 (-5835 700);
PAINT SKYBLUE (-5835 700);
FORCEPROP 1 LAST PART_NUMBER G21796-007
J 0
(-5835 750);
DISPLAY 0.617021 (-5835 750);
PAINT BLUE (-5835 750);
FORCEPROP 1 LAST MATERIAL CHIP
J 0
(-5835 800);
DISPLAY 0.617021 (-5835 800);
PAINT SKYBLUE (-5835 800);
FORCEPROP 1 LAST WATTAGE 1/16W
J 0
(-5835 850);
DISPLAY 0.617021 (-5835 850);
PAINT SKYBLUE (-5835 850);
FORCEPROP 2 LAST ROOM HOT_SWAP
J 0
(-5825 1050);
PAINT MONO (-5825 1050);
DISPLAY INVISIBLE (-5825 1050);
FORCEPROP 1 LAST PATH I85
J 0
(-5825 1050);
DISPLAY 0.978723 (-5825 1050);
PAINT WHITE (-5825 1050);
DISPLAY INVISIBLE (-5825 1050);
FORCEPROP 0 LAST NO_XNET_CONNECTION 1
J 0
(-5825 1100);
PAINT MONO (-5825 1100);
DISPLAY INVISIBLE (-5825 1100);
FORCEPROP 2 LAST SEC 1
J 0
(-5825 1100);
DISPLAY 0.680851 (-5825 1100);
PAINT MONO (-5825 1100);
DISPLAY INVISIBLE (-5825 1100);
FORCEPROP 2 LAST SEC_TYPE 0402
J 0
(-5825 1100);
DISPLAY 1.021277 (-5825 1100);
PAINT ORANGE (-5825 1100);
DISPLAY INVISIBLE (-5825 1100);
FORCEPROP 2 LAST CDS_LOCATION R1D16
J 0
(-5830 1000);
DISPLAY 0.617021 (-5830 1000);
PAINT AQUA (-5830 1000);
DISPLAY INVISIBLE (-5830 1000);
FORCEPROP 2 LAST CDS_LIB mstr_discrete
J 0
(-5875 875);
PAINT ORANGE (-5875 875);
DISPLAY INVISIBLE (-5875 875);
FORCEADD FET_N_DUAL..5
(-5875 275);
FORCEPROP 1 LASTPIN (-5875 475) $PN 6
J 2
(-5822 440);
DISPLAY 0.617021 (-5822 440);
PAINT WHITE (-5822 440);
FORCEPROP 1 LAST LOCATION Q1D1
J 0
(-5675 275);
DISPLAY 0.617021 (-5675 275);
PAINT AQUA (-5675 275);
FORCEPROP 1 LASTPIN (-6075 175) $PN 2
J 2
(-6072 190);
DISPLAY 0.617021 (-6072 190);
PAINT WHITE (-6072 190);
FORCEPROP 1 LASTPIN (-5875 75) $PN 1
J 2
(-5817 75);
DISPLAY 0.617021 (-5817 75);
PAINT WHITE (-5817 75);
FORCEPROP 1 LAST MATERIAL FET
J 0
(-5675 175);
DISPLAY 0.617021 (-5675 175);
PAINT SKYBLUE (-5675 175);
FORCEPROP 1 LAST VALUE 2N7002DW
J 0
(-5675 225);
DISPLAY 0.617021 (-5675 225);
PAINT SKYBLUE (-5675 225);
FORCEPROP 1 LAST PART_NUMBER D24280-001
J 0
(-5675 125);
DISPLAY 0.617021 (-5675 125);
PAINT BLUE (-5675 125);
FORCEPROP 2 LAST ROOM HOT_SWAP
J 0
(-5675 375);
PAINT MONO (-5675 375);
DISPLAY INVISIBLE (-5675 375);
FORCEPROP 1 LAST PATH I86
J 0
(-5675 325);
DISPLAY 0.978723 (-5675 325);
PAINT BLUE (-5675 325);
DISPLAY INVISIBLE (-5675 325);
FORCEPROP 2 LAST CDS_LOCATION Q1D1
J 0
(-5675 275);
DISPLAY 0.617021 (-5675 275);
PAINT AQUA (-5675 275);
DISPLAY INVISIBLE (-5675 275);
FORCEPROP 2 LAST SEC 1
J 0
(-5675 375);
DISPLAY 0.680851 (-5675 375);
PAINT MONO (-5675 375);
DISPLAY INVISIBLE (-5675 375);
FORCEPROP 2 LAST SEC_TYPE SMLF
J 0
(-5675 375);
DISPLAY 1.021277 (-5675 375);
PAINT ORANGE (-5675 375);
DISPLAY INVISIBLE (-5675 375);
FORCEPROP 2 LAST CDS_LIB mstr_discrete
J 0
(-5875 275);
PAINT ORANGE (-5875 275);
DISPLAY INVISIBLE (-5875 275);
FORCEPROP 1 LAST PACK_TYPE SMLF
J 0
(-5675 125);
DISPLAY 0.978723 (-5675 125);
PAINT SKYBLUE (-5675 125);
DISPLAY INVISIBLE (-5675 125);
FORCEADD RES..2
(-6950 -50);
FORCEPROP 1 LAST VALUE 100.0K
J 0
(-6905 25);
DISPLAY 0.617021 (-6905 25);
PAINT SKYBLUE (-6905 25);
FORCEPROP 1 LAST TOLERANCE 1%
J 0
(-6905 -25);
DISPLAY 0.617021 (-6905 -25);
PAINT SKYBLUE (-6905 -25);
FORCEPROP 1 LASTPIN (-6950 -150) $PN 2
J 0
(-6945 -140);
DISPLAY 0.617021 (-6945 -140);
PAINT ORANGE (-6945 -140);
FORCEPROP 1 LAST PACK_TYPE 0402
J 0
(-6910 -225);
DISPLAY 0.617021 (-6910 -225);
PAINT SKYBLUE (-6910 -225);
FORCEPROP 1 LASTPIN (-6950 50) $PN 1
J 0
(-6945 12);
DISPLAY 0.617021 (-6945 12);
PAINT ORANGE (-6945 12);
FORCEPROP 1 LAST LOCATION R1D18
J 0
(-6905 75);
DISPLAY 0.617021 (-6905 75);
PAINT AQUA (-6905 75);
FORCEPROP 1 LAST PART_NUMBER G21796-010
J 0
(-6910 -175);
DISPLAY 0.617021 (-6910 -175);
PAINT BLUE (-6910 -175);
FORCEPROP 1 LAST MATERIAL CHIP
J 0
(-6910 -125);
DISPLAY 0.617021 (-6910 -125);
PAINT SKYBLUE (-6910 -125);
FORCEPROP 1 LAST WATTAGE 1/16W
J 0
(-6910 -75);
DISPLAY 0.617021 (-6910 -75);
PAINT SKYBLUE (-6910 -75);
FORCEPROP 2 LAST CDS_LIB mstr_discrete
J 0
(-6950 -50);
PAINT ORANGE (-6950 -50);
DISPLAY INVISIBLE (-6950 -50);
FORCEPROP 2 LAST SEC_TYPE 0402
J 0
(-6900 175);
DISPLAY 1.021277 (-6900 175);
PAINT ORANGE (-6900 175);
DISPLAY INVISIBLE (-6900 175);
FORCEPROP 2 LAST SEC 1
J 0
(-6900 175);
DISPLAY 0.680851 (-6900 175);
PAINT MONO (-6900 175);
DISPLAY INVISIBLE (-6900 175);
FORCEPROP 2 LAST CDS_LOCATION R1D18
J 0
(-6905 75);
DISPLAY 0.617021 (-6905 75);
PAINT AQUA (-6905 75);
DISPLAY INVISIBLE (-6905 75);
FORCEPROP 2 LAST ROOM HOT_SWAP
J 0
(-6900 125);
PAINT MONO (-6900 125);
DISPLAY INVISIBLE (-6900 125);
FORCEPROP 1 LAST PATH I87
J 0
(-6900 125);
DISPLAY 0.978723 (-6900 125);
PAINT WHITE (-6900 125);
DISPLAY INVISIBLE (-6900 125);
FORCEADD RES..2
(-6300 -50);
FORCEPROP 1 LAST LOCATION R1D11
J 0
(-6255 75);
DISPLAY 0.617021 (-6255 75);
PAINT AQUA (-6255 75);
FORCEPROP 1 LASTPIN (-6300 50) $PN 1
J 0
(-6295 12);
DISPLAY 0.617021 (-6295 12);
PAINT ORANGE (-6295 12);
FORCEPROP 1 LAST VALUE 100.0K
J 0
(-6255 25);
DISPLAY 0.617021 (-6255 25);
PAINT SKYBLUE (-6255 25);
FORCEPROP 1 LAST TOLERANCE 1%
J 0
(-6255 -25);
DISPLAY 0.617021 (-6255 -25);
PAINT SKYBLUE (-6255 -25);
FORCEPROP 1 LAST WATTAGE 1/16W
J 0
(-6260 -75);
DISPLAY 0.617021 (-6260 -75);
PAINT SKYBLUE (-6260 -75);
FORCEPROP 1 LAST MATERIAL CHIP
J 0
(-6260 -125);
DISPLAY 0.617021 (-6260 -125);
PAINT SKYBLUE (-6260 -125);
FORCEPROP 1 LAST PART_NUMBER G21796-010
J 0
(-6260 -175);
DISPLAY 0.617021 (-6260 -175);
PAINT BLUE (-6260 -175);
FORCEPROP 1 LAST PACK_TYPE 0402
J 0
(-6260 -225);
DISPLAY 0.617021 (-6260 -225);
PAINT SKYBLUE (-6260 -225);
FORCEPROP 1 LASTPIN (-6300 -150) $PN 2
J 0
(-6295 -140);
DISPLAY 0.617021 (-6295 -140);
PAINT ORANGE (-6295 -140);
FORCEPROP 2 LAST SEC_TYPE 0402
J 0
(-6250 175);
DISPLAY 1.021277 (-6250 175);
PAINT ORANGE (-6250 175);
DISPLAY INVISIBLE (-6250 175);
FORCEPROP 2 LAST SEC 1
J 0
(-6250 175);
DISPLAY 0.680851 (-6250 175);
PAINT MONO (-6250 175);
DISPLAY INVISIBLE (-6250 175);
FORCEPROP 2 LAST CDS_LOCATION R1D11
J 0
(-6255 75);
DISPLAY 0.617021 (-6255 75);
PAINT AQUA (-6255 75);
DISPLAY INVISIBLE (-6255 75);
FORCEPROP 1 LAST PATH I88
J 0
(-6250 125);
DISPLAY 0.978723 (-6250 125);
PAINT WHITE (-6250 125);
DISPLAY INVISIBLE (-6250 125);
FORCEPROP 2 LAST ROOM HOT_SWAP
J 0
(-6250 125);
PAINT MONO (-6250 125);
DISPLAY INVISIBLE (-6250 125);
FORCEPROP 2 LAST CDS_LIB mstr_discrete
J 0
(-6300 -50);
PAINT ORANGE (-6300 -50);
DISPLAY INVISIBLE (-6300 -50);
FORCEADD AGND0..1
(-6300 -325);
FORCEPROP 3 LASTPIN (-6300 -275) SIG_NAME AGND_HSC\g
J 0
(-6290 -265);
DISPLAY 0.659574 (-6290 -265);
PAINT MONO (-6290 -265);
DISPLAY INVISIBLE (-6290 -265);
FORCEPROP 1 LAST HDL_POWER AGND_HSC
J 1
(-6300 -375);
DISPLAY 0.617021 (-6300 -375);
PAINT GREEN (-6300 -375);
FORCEPROP 1 LAST BODY_TYPE PLUMBING
J 0
(-6345 -368);
DISPLAY 0.340426 (-6345 -368);
PAINT GREEN (-6345 -368);
DISPLAY INVISIBLE (-6345 -368);
FORCEPROP 2 LAST ROOM VR_P3V3
J 0
(-6325 -350);
PAINT ORANGE (-6325 -350);
DISPLAY INVISIBLE (-6325 -350);
FORCEPROP 1 LAST PATH I89
J 0
(-6225 -325);
DISPLAY 0.872340 (-6225 -325);
PAINT AQUA (-6225 -325);
DISPLAY INVISIBLE (-6225 -325);
FORCEPROP 2 LAST CDS_LIB mstr_symbols
J 0
(-6300 -325);
PAINT ORANGE (-6300 -325);
DISPLAY INVISIBLE (-6300 -325);
FORCEPROP 2 LAST BOM_COST MIO_VRD_MAIN
J 0
(-6275 -350);
PAINT ORANGE (-6275 -350);
DISPLAY INVISIBLE (-6275 -350);
FORCEPROP 1 LAST VOLTAGE 0
J 0
(-6300 -325);
PAINT SKYBLUE (-6300 -325);
DISPLAY INVISIBLE (-6300 -325);
FORCEADD RES..2
(-7200 3625);
FORCEPROP 1 LAST PACK_TYPE 0402
J 0
(-7160 3450);
DISPLAY 0.617021 (-7160 3450);
PAINT SKYBLUE (-7160 3450);
FORCEPROP 1 LAST PART_NUMBER G21796-177
J 0
(-7160 3500);
DISPLAY 0.617021 (-7160 3500);
PAINT BLUE (-7160 3500);
FORCEPROP 1 LASTPIN (-7200 3525) $PN 2
J 0
(-7195 3535);
DISPLAY 0.617021 (-7195 3535);
PAINT ORANGE (-7195 3535);
FORCEPROP 1 LAST MATERIAL CHIP
J 0
(-7160 3550);
DISPLAY 0.617021 (-7160 3550);
PAINT SKYBLUE (-7160 3550);
FORCEPROP 1 LAST TOLERANCE 1%
J 0
(-7155 3650);
DISPLAY 0.617021 (-7155 3650);
PAINT SKYBLUE (-7155 3650);
FORCEPROP 1 LAST VALUE 7.5K
J 0
(-7155 3700);
DISPLAY 0.617021 (-7155 3700);
PAINT SKYBLUE (-7155 3700);
FORCEPROP 1 LAST LOCATION R1D43
J 0
(-7155 3750);
DISPLAY 0.617021 (-7155 3750);
PAINT AQUA (-7155 3750);
FORCEPROP 0 LAST CONFIG 064.7501D.06DD
J 0
(-7525 3375);
DISPLAY 0.638298 (-7525 3375);
PAINT BROWN (-7525 3375);
DISPLAY BOTH (-7525 3375);
FORCEPROP 1 LAST WATTAGE 1/16W
J 0
(-7160 3600);
DISPLAY 0.617021 (-7160 3600);
PAINT SKYBLUE (-7160 3600);
FORCEPROP 1 LASTPIN (-7200 3725) $PN 1
J 0
(-7195 3687);
DISPLAY 0.617021 (-7195 3687);
PAINT ORANGE (-7195 3687);
FORCEPROP 2 LAST SEC_TYPE 0402
J 0
(-7150 3850);
DISPLAY 1.021277 (-7150 3850);
PAINT ORANGE (-7150 3850);
DISPLAY INVISIBLE (-7150 3850);
FORCEPROP 2 LAST SEC 1
J 0
(-7150 3850);
DISPLAY 0.680851 (-7150 3850);
PAINT MONO (-7150 3850);
DISPLAY INVISIBLE (-7150 3850);
FORCEPROP 2 LAST CDS_LOCATION R1D43
J 0
(-7155 3750);
DISPLAY 0.617021 (-7155 3750);
PAINT AQUA (-7155 3750);
DISPLAY INVISIBLE (-7155 3750);
FORCEPROP 1 LAST PATH I9
J 0
(-7150 3800);
DISPLAY 0.978723 (-7150 3800);
PAINT WHITE (-7150 3800);
DISPLAY INVISIBLE (-7150 3800);
FORCEPROP 0 LAST ROOM HOT_SWAP
J 0
(-7150 3800);
DISPLAY 1.021277 (-7150 3800);
PAINT ORANGE (-7150 3800);
DISPLAY INVISIBLE (-7150 3800);
FORCEPROP 2 LAST CDS_LIB mstr_discrete
J 0
(-7200 3625);
PAINT ORANGE (-7200 3625);
DISPLAY INVISIBLE (-7200 3625);
FORCEADD P12V_PSU..1
(-7300 950);
FORCEPROP 3 LASTPIN (-7300 900) SIG_NAME P12V_PSU\g
J 0
(-7290 910);
DISPLAY 0.659574 (-7290 910);
PAINT MONO (-7290 910);
DISPLAY INVISIBLE (-7290 910);
FORCEPROP 1 LAST HDL_POWER P12V_PSU
J 1
(-7300 1000);
DISPLAY 0.872340 (-7300 1000);
PAINT GREEN (-7300 1000);
DISPLAY INVISIBLE (-7300 1000);
FORCEPROP 1 LAST BODY_TYPE PLUMBING
J 0
(-7345 907);
DISPLAY 0.340426 (-7345 907);
PAINT GREEN (-7345 907);
DISPLAY INVISIBLE (-7345 907);
FORCEPROP 2 LAST ROOM P2V5_LAN_AUX_VR
J 0
(-7300 1050);
DISPLAY 0.617021 (-7300 1050);
PAINT ORANGE (-7300 1050);
DISPLAY INVISIBLE (-7300 1050);
FORCEPROP 2 LAST BOM_COST NT_BASE_VRD
J 0
(-7300 1050);
DISPLAY 0.617021 (-7300 1050);
PAINT ORANGE (-7300 1050);
DISPLAY INVISIBLE (-7300 1050);
FORCEPROP 1 LAST PATH I90
J 0
(-7250 975);
DISPLAY 0.872340 (-7250 975);
PAINT AQUA (-7250 975);
DISPLAY INVISIBLE (-7250 975);
FORCEPROP 1 LAST VOLTAGE 12.0
J 0
(-7345 907);
DISPLAY 0.340426 (-7345 907);
PAINT SKYBLUE (-7345 907);
DISPLAY INVISIBLE (-7345 907);
FORCEPROP 2 LAST CDS_LIB mstr_symbols
J 0
(-7300 950);
PAINT ORANGE (-7300 950);
DISPLAY INVISIBLE (-7300 950);
FORCEADD RES..2
(-7300 750);
FORCEPROP 1 LAST LOCATION R1D15
J 0
(-7255 875);
DISPLAY 0.617021 (-7255 875);
PAINT AQUA (-7255 875);
FORCEPROP 1 LAST WATTAGE 1/16W
J 0
(-7260 725);
DISPLAY 0.617021 (-7260 725);
PAINT SKYBLUE (-7260 725);
FORCEPROP 1 LAST PART_NUMBER G21796-010
J 0
(-7250 625);
DISPLAY 0.617021 (-7250 625);
PAINT BLUE (-7250 625);
FORCEPROP 1 LAST VALUE 100.0K
J 0
(-7255 825);
DISPLAY 0.617021 (-7255 825);
PAINT SKYBLUE (-7255 825);
FORCEPROP 1 LAST TOLERANCE 1%
J 0
(-7255 775);
DISPLAY 0.617021 (-7255 775);
PAINT SKYBLUE (-7255 775);
FORCEPROP 1 LASTPIN (-7300 850) $PN 1
J 0
(-7295 812);
DISPLAY 0.617021 (-7295 812);
PAINT ORANGE (-7295 812);
FORCEPROP 1 LAST PACK_TYPE 0402
J 0
(-7250 575);
DISPLAY 0.617021 (-7250 575);
PAINT SKYBLUE (-7250 575);
FORCEPROP 1 LAST MATERIAL CHIP
J 0
(-7260 675);
DISPLAY 0.617021 (-7260 675);
PAINT SKYBLUE (-7260 675);
FORCEPROP 1 LASTPIN (-7300 650) $PN 2
J 0
(-7295 660);
DISPLAY 0.617021 (-7295 660);
PAINT ORANGE (-7295 660);
FORCEPROP 2 LAST ROOM HOT_SWAP
J 0
(-7250 925);
PAINT MONO (-7250 925);
DISPLAY INVISIBLE (-7250 925);
FORCEPROP 1 LAST PATH I92
J 0
(-7250 925);
DISPLAY 0.978723 (-7250 925);
PAINT WHITE (-7250 925);
DISPLAY INVISIBLE (-7250 925);
FORCEPROP 2 LAST CDS_LOCATION R1D15
J 0
(-7255 875);
DISPLAY 0.617021 (-7255 875);
PAINT AQUA (-7255 875);
DISPLAY INVISIBLE (-7255 875);
FORCEPROP 2 LAST SEC 1
J 0
(-7250 975);
DISPLAY 0.680851 (-7250 975);
PAINT MONO (-7250 975);
DISPLAY INVISIBLE (-7250 975);
FORCEPROP 2 LAST SEC_TYPE 0402
J 0
(-7250 975);
DISPLAY 1.021277 (-7250 975);
PAINT ORANGE (-7250 975);
DISPLAY INVISIBLE (-7250 975);
FORCEPROP 2 LAST CDS_LIB mstr_discrete
J 0
(-7300 750);
PAINT ORANGE (-7300 750);
DISPLAY INVISIBLE (-7300 750);
FORCEADD OFFPAGE..2
R 2
(-6000 2825);
FORCEPROP 2 LAST $XR0 200 
J 0
(-6255 2825);
DISPLAY 0.638298 (-6255 2825);
PAINT MONO (-6255 2825);
FORCEPROP 2 LAST CDS_LIB mstr_standard
J 0
(-6000 2825);
PAINT MONO (-6000 2825);
DISPLAY INVISIBLE (-6000 2825);
FORCEPROP 2 LAST PATH I98
J 0
(-5950 2900);
DISPLAY 1.021277 (-5950 2900);
PAINT ORANGE (-5950 2900);
DISPLAY INVISIBLE (-5950 2900);
FORCEPROP 1 LAST OFFPAGE TRUE
J 2
(-6325 2700);
DISPLAY 0.872340 (-6325 2700);
PAINT GREEN (-6325 2700);
DISPLAY INVISIBLE (-6325 2700);
FORCEPROP 1 LAST COMMENT_BODY TRUE
J 2
(-5955 2730);
DISPLAY 0.872340 (-5955 2730);
PAINT GREEN (-5955 2730);
DISPLAY INVISIBLE (-5955 2730);
FORCEADD ZENER..4
(-5100 3875);
FORCEPROP 0 LAST NEW_VALUE 14V
J 0
(-4975 3900);
DISPLAY 0.638298 (-4975 3900);
PAINT BROWN (-4975 3900);
DISPLAY BOTH (-4975 3900);
FORCEPROP 1 LAST LOCATION VR1D1
J 0
(-4975 3950);
DISPLAY 0.617021 (-4975 3950);
PAINT AQUA (-4975 3950);
FORCEPROP 1 LASTPIN (-5100 4025) $PN 1
J 0
(-5080 3995);
DISPLAY 0.617021 (-5080 3995);
PAINT AQUA (-5080 3995);
FORCEPROP 1 LAST PACK_TYPE SM
J 0
(-4975 3800);
DISPLAY 0.617021 (-4975 3800);
PAINT SKYBLUE (-4975 3800);
FORCEPROP 1 LASTPIN (-5100 3775) $PN 2
J 0
(-5080 3780);
DISPLAY 0.617021 (-5080 3780);
PAINT AQUA (-5080 3780);
FORCEPROP 1 LAST MATERIAL IC
J 0
(-4975 3850);
DISPLAY 0.617021 (-4975 3850);
PAINT SKYBLUE (-4975 3850);
FORCEPROP 0 LAST NEW_PN 083.01514.00AD
J 0
(-4975 3750);
DISPLAY 0.638298 (-4975 3750);
PAINT BROWN (-4975 3750);
DISPLAY BOTH (-4975 3750);
FORCEPROP 1 LAST VALUE 13V
J 0
(-4975 3900);
DISPLAY 0.617021 (-4975 3900);
PAINT SKYBLUE (-4975 3900);
DISPLAY INVISIBLE (-4975 3900);
FORCEPROP 2 LAST SEC_TYPE SM
J 0
(-4975 4050);
DISPLAY 1.021277 (-4975 4050);
PAINT ORANGE (-4975 4050);
DISPLAY INVISIBLE (-4975 4050);
FORCEPROP 2 LAST CDS_LIB mstr_discrete
J 0
(-5100 3875);
PAINT MONO (-5100 3875);
DISPLAY INVISIBLE (-5100 3875);
FORCEPROP 2 LAST SEC 1
J 0
(-4975 4050);
PAINT MONO (-4975 4050);
DISPLAY INVISIBLE (-4975 4050);
FORCEPROP 2 LAST CDS_LOCATION VR1D1
J 0
(-4975 3950);
DISPLAY 0.617021 (-4975 3950);
PAINT AQUA (-4975 3950);
DISPLAY INVISIBLE (-4975 3950);
FORCEPROP 1 LAST PATH I99
J 0
(-4975 4000);
DISPLAY 0.978723 (-4975 4000);
PAINT BLUE (-4975 4000);
DISPLAY INVISIBLE (-4975 4000);
FORCEPROP 1 LAST PART_NUMBER H69095-001
J 0
(-4975 3750);
DISPLAY 0.617021 (-4975 3750);
PAINT BLUE (-4975 3750);
DISPLAY INVISIBLE (-4975 3750);
FORCEADD DNS..2
(-395 2620);
PAINT RED (-395 2620);
FORCEPROP 1 LAST COMMENT_BODY TRUE
R 1
J 0
(-320 2395);
DISPLAY 0.872340 (-320 2395);
PAINT GREEN (-320 2395);
DISPLAY INVISIBLE (-320 2395);
FORCEPROP 2 LAST CDS_LIB mstr_misc
J 0
(-395 2620);
PAINT ORANGE (-395 2620);
DISPLAY INVISIBLE (-395 2620);
FORCEADD INTEL_CORP_BPAGE..1
(-100 -425);
FORCEPROP 1 LAST CDS_CON_LAST_MODIFIED Fri Jun 16 17:49:13 2017
J 0
(-1525 -100);
PAINT GREEN (-1525 -100);
DISPLAY INVISIBLE (-1525 -100);
FORCEPROP 1 LAST CUSTOM_TXT_CDS <CURRENT_DESIGN_SHEET> OF <TOTAL_DESIGN_SHEETS>
J 0
(-600 -400);
PAINT ORANGE (-600 -400);
FORCEPROP 1 LAST CUSTOM_TXT_CDS <CON_LAST_MODIFIED>
J 0
(-4100 -325);
PAINT ORANGE (-4100 -325);
FORCEPROP 2 LAST CUSTOM_TXT_CDS <XR_PAGE_TITLE>
J 0
(-7990 4825);
DISPLAY 0.638298 (-7990 4825);
PAINT PINK (-7990 4825);
DISPLAY INVISIBLE (-7990 4825);
FORCEPROP 1 LAST SCH_TITLE HOT SWAP CONTROLLER (1/2)
J 0
(-7950 -300);
DISPLAY 1.212766 (-7950 -300);
PAINT ORANGE (-7950 -300);
FORCEPROP 1 LAST COMMENT_BODY TRUE
J 0
(-88 -413);
DISPLAY 0.468085 (-88 -413);
PAINT GREEN (-88 -413);
DISPLAY INVISIBLE (-88 -413);
FORCEPROP 2 LAST PAGE_BORDER TRUE
J 0
(-7990 4825);
DISPLAY 0.851064 (-7990 4825);
PAINT PINK (-7990 4825);
DISPLAY INVISIBLE (-7990 4825);
FORCEPROP 2 LAST CDS_LIB mstr_symbols
J 0
(-100 -425);
PAINT ORANGE (-100 -425);
DISPLAY INVISIBLE (-100 -425);
FORCEPROP 2 LAST CDS_XR_PAGE_TITLE CR-199 : @BASEBOARD_FAB2_LIB.BASEBOARD_FAB2(SCH_1):PAGE199
J 0
(-7990 4825);
DISPLAY 0.638298 (-7990 4825);
PAINT PINK (-7990 4825);
DISPLAY INVISIBLE (-7990 4825);
FORCEADD DESIGN_NOTE..1
(-7825 1675);
FORCEPROP 0 LAST L3 POWER CONNECTOR
J 0
(-8025 1400);
DISPLAY 0.808511 (-8025 1400);
PAINT ORANGE (-8025 1400);
FORCEPROP 0 LAST L1 D53458-001 EMPTY LOCATION
J 0
(-8025 1550);
DISPLAY 0.808511 (-8025 1550);
PAINT ORANGE (-8025 1550);
FORCEPROP 0 LAST L2 TO BE USED WHEN USING TYCO
J 0
(-8025 1475);
DISPLAY 0.808511 (-8025 1475);
PAINT ORANGE (-8025 1475);
FORCEPROP 1 LAST COMMENT_BODY TRUE
J 0
(-7800 1775);
DISPLAY 0.978723 (-7800 1775);
PAINT ORANGE (-7800 1775);
DISPLAY INVISIBLE (-7800 1775);
FORCEPROP 2 LAST CDS_LIB mstr_symbols
J 0
(-7825 1675);
PAINT ORANGE (-7825 1675);
DISPLAY INVISIBLE (-7825 1675);
FORCEADD DNS..2
(-4620 1020);
PAINT RED (-4620 1020);
FORCEPROP 1 LAST COMMENT_BODY TRUE
R 1
J 0
(-4545 795);
DISPLAY 0.872340 (-4545 795);
PAINT GREEN (-4545 795);
DISPLAY INVISIBLE (-4545 795);
FORCEPROP 2 LAST CDS_LIB mstr_misc
J 0
(-4620 1020);
PAINT ORANGE (-4620 1020);
DISPLAY INVISIBLE (-4620 1020);
FORCEADD DNS..2
(-7670 2945);
PAINT RED (-7670 2945);
FORCEPROP 2 LAST CDS_LIB mstr_misc
J 0
(-7670 2945);
PAINT ORANGE (-7670 2945);
DISPLAY INVISIBLE (-7670 2945);
FORCEPROP 1 LAST COMMENT_BODY TRUE
R 1
J 0
(-7595 2720);
DISPLAY 0.872340 (-7595 2720);
PAINT GREEN (-7595 2720);
DISPLAY INVISIBLE (-7595 2720);
FORCEADD DESIGN_NOTE..1
(-4375 725);
FORCEPROP 1 LAST COMMENT_BODY TRUE
J 0
(-4350 825);
DISPLAY 1.319149 (-4350 825);
PAINT WHITE (-4350 825);
DISPLAY INVISIBLE (-4350 825);
FORCEPROP 2 LAST BOM_COST SM_CONTROLLER
J 0
(-4575 675);
PAINT WHITE (-4575 675);
DISPLAY INVISIBLE (-4575 675);
FORCEPROP 2 LAST CDS_LIB mstr_symbols
J 0
(-4375 725);
PAINT ORANGE (-4375 725);
DISPLAY INVISIBLE (-4375 725);
FORCEPROP 2 LAST ROOM BMC
J 0
(-4575 675);
PAINT WHITE (-4575 675);
DISPLAY INVISIBLE (-4575 675);
WIRE 16 -1 (-5400 575)(-5400 500);
WIRE 16 -1 (-5300 575)(-5400 575);
WIRE 16 -1 (-5400 575)(-5600 575);
WIRE 16 -1 (-5600 650)(-5600 575);
WIRE 16 -1 (-5300 700)(-5300 575);
WIRE 16 -1 (-6150 650)(-6150 750);
WIRE 16 -1 (-2150 2325)(-2150 2525);
WIRE 16 -1 (-2500 2525)(-2150 2525);
WIRE 16 -1 (-6600 25)(-6600 200);
WIRE 16 -1 (-7200 3300)(-7200 3325);
WIRE 16 -1 (-6775 3325)(-7200 3325);
WIRE 16 -1 (-7200 3525)(-7200 3325);
WIRE 16 -1 (-6775 3475)(-6775 3325);
WIRE 16 -1 (-5525 3400)(-5525 3500);
WIRE 16 -1 (-5100 3775)(-5100 3450);
WIRE 16 -1 (-6375 3350)(-6375 3325);
WIRE 16 -1 (-6375 3350)(-6075 3350);
WIRE 16 -1 (-6500 3350)(-6375 3350);
WIRE 16 -1 (-6500 3500)(-6500 3350);
WIRE 16 -1 (-6075 3475)(-6075 3350);
WIRE 16 -1 (-2375 2425)(-2375 2350);
WIRE 16 -1 (-2500 2425)(-2375 2425);
WIRE 16 -1 (-5650 1900)(-5650 1850);
WIRE 16 -1 (-5000 150)(-5000 325);
WIRE 16 -1 (-3350 -50)(-3350 0);
WIRE 16 -1 (-1500 1550)(-1500 1500);
WIRE 16 -1 (-1500 1550)(-1350 1550);
WIRE 16 -1 (-1500 1600)(-1500 1550);
WIRE 16 -1 (-1350 200)(-1350 300);
WIRE 16 -1 (-1350 300)(-1550 300);
WIRE 16 -1 (-1950 300)(-1950 200);
WIRE 16 -1 (-1750 300)(-1950 300);
WIRE 16 -1 (-2000 2625)(-2000 2425);
WIRE 16 -1 (-2500 2625)(-2000 2625);
WIRE 16 -1 (-4725 750)(-4725 675);
WIRE 16 -1 (-4850 750)(-4725 750);
WIRE 16 -1 (-4625 750)(-4725 750);
WIRE 16 -1 (-4625 925)(-4625 750);
WIRE 16 -1 (-4850 1400)(-4850 750);
WIRE 16 -1 (-7675 2125)(-7675 2150);
WIRE 16 -1 (-8000 2150)(-7675 2150);
WIRE 16 -1 (-7675 2275)(-7675 2150);
WIRE 16 -1 (-8000 2150)(-8000 2275);
WIRE 16 -1 (-2825 650)(-2825 600);
WIRE 16 -1 (-7025 2075)(-7025 2025);
WIRE 16 -1 (-6725 1625)(-6725 1575);
WIRE 16 -1 (-400 2525)(-400 2450);
WIRE 16 -1 (-400 3125)(-400 3550);
WIRE 16 -1 (-6725 2125)(-6725 2200);
WIRE 16 -1 (-3125 1175)(-3125 1225);
WIRE 16 -1 (-6675 4375)(-6675 4225);
WIRE 16 -1 (-6675 4225)(-6500 4225);
WIRE 16 -1 (-7200 4225)(-6675 4225);
WIRE 16 -1 (-7200 4125)(-7200 4225);
WIRE 16 -1 (-5525 4225)(-6500 4225);
WIRE 16 -1 (-6500 4150)(-6500 4225);
WIRE 16 -1 (-5525 4225)(-5100 4225);
WIRE 16 -1 (-5525 4125)(-5525 4225);
WIRE 16 -1 (-5100 4225)(-5100 4025);
WIRE 16 -1 (-5875 25)(-5875 75);
WIRE 16 -1 (-6300 -225)(-6300 -275);
WIRE 16 -1 (-6950 -225)(-6300 -225);
WIRE 16 -1 (-6300 -225)(-6300 -150);
WIRE 16 -1 (-6950 -150)(-6950 -225);
WIRE 16 -1 (-7300 850)(-7300 900);
WIRE 16 -1 (-7200 3725)(-7200 3800);
WIRE 16 -1 (-7200 3925)(-7200 3800);
WIRE 16 -1 (-7200 3800)(-6775 3800);
WIRE 16 -1 (-6775 3800)(-6775 3675);
WIRE 16 -1 (-6700 3800)(-6775 3800);
WIRE 16 -1 (-6700 3800)(-6700 3075);
WIRE 16 -1 (-6700 3075)(-4000 3075);
FORCEPROP 0 LAST SIG_NAME A_HSC_OV
J 0
(-4635 3085);
DISPLAY 0.617021 (-4635 3085);
PAINT ORANGE (-4635 3085);
FORCEPROP 2 LASTPROP $XRERR UNIQUE?
J 0
(-4875 3085);
DISPLAY 0.638298 (-4875 3085);
PAINT MONO (-4875 3085);
DISPLAY INVISIBLE (-4875 3085);
WIRE 16 -1 (-6500 3800)(-6500 3700);
WIRE 16 -1 (-6500 3950)(-6500 3800);
WIRE 16 -1 (-6075 3800)(-6500 3800);
WIRE 16 -1 (-6075 3675)(-6075 3800);
WIRE 16 -1 (-6000 3800)(-6075 3800);
WIRE 16 -1 (-6000 3800)(-6000 3125);
WIRE 16 -1 (-4000 3125)(-6000 3125);
FORCEPROP 0 LAST SIG_NAME A_HSC_UV
J 0
(-4635 3135);
DISPLAY 0.617021 (-4635 3135);
PAINT ORANGE (-4635 3135);
FORCEPROP 2 LASTPROP $XRERR UNIQUE?
J 0
(-4875 3135);
DISPLAY 0.638298 (-4875 3135);
PAINT MONO (-4875 3135);
DISPLAY INVISIBLE (-4875 3135);
WIRE 16 -1 (-5525 3700)(-5525 3825);
WIRE 16 -1 (-5525 3825)(-5525 3925);
WIRE 16 -1 (-5650 3825)(-5525 3825);
WIRE 16 -1 (-5650 3275)(-5650 3825);
WIRE 16 -1 (-4000 3275)(-5650 3275);
FORCEPROP 0 LAST VOLTAGE +12V
J 0
(-4625 3350);
DISPLAY 1.021277 (-4625 3350);
PAINT SKYBLUE (-4625 3350);
DISPLAY INVISIBLE (-4625 3350);
FORCEPROP 0 LAST SIG_NAME P12V_HSC_VCC
J 0
(-4635 3285);
DISPLAY 0.617021 (-4635 3285);
PAINT ORANGE (-4635 3285);
FORCEPROP 2 LASTPROP $XRERR UNIQUE?
J 0
(-4875 3285);
DISPLAY 0.638298 (-4875 3285);
PAINT MONO (-4875 3285);
DISPLAY INVISIBLE (-4875 3285);
WIRE 16 -1 (-6600 1650)(-6600 1700);
WIRE 16 -1 (-6600 1700)(-5600 1700);
WIRE 16 -1 (-5600 1600)(-5600 1700);
WIRE 16 -1 (-5300 1700)(-5600 1700);
WIRE 16 -1 (-5300 1600)(-5300 1700);
WIRE 16 -1 (-7675 3050)(-7675 3125);
WIRE 16 -1 (-8000 3050)(-8000 3125);
WIRE 16 -1 (-8000 3125)(-7825 3125);
WIRE 16 -1 (-7825 3125)(-7675 3125);
WIRE 16 -1 (-5650 2100)(-5650 2150);
WIRE 16 -1 (-5100 1700)(-5300 1700);
WIRE 16 -1 (-5100 1700)(-5100 2150);
WIRE 16 -1 (-5650 2150)(-5100 2150);
WIRE 16 -1 (-7825 3175)(-7825 3125);
WIRE 16 -1 (-7825 3175)(-5100 3175);
WIRE 16 -1 (-5100 2150)(-5100 3175);
WIRE 16 -1 (-4000 3175)(-5100 3175);
FORCEPROP 0 LAST SIG_NAME A_HSC_VCAP
J 0
(-4635 3185);
DISPLAY 0.617021 (-4635 3185);
PAINT ORANGE (-4635 3185);
FORCEPROP 2 LASTPROP $XRERR UNIQUE?
J 0
(-4875 3185);
DISPLAY 0.638298 (-4875 3185);
PAINT MONO (-4875 3185);
DISPLAY INVISIBLE (-4875 3185);
WIRE 16 -1 (-5300 900)(-5300 1050);
WIRE 16 -1 (-5300 1050)(-5300 1400);
WIRE 16 -1 (-5000 1050)(-5300 1050);
WIRE 16 -1 (-5000 525)(-5000 1050);
WIRE 16 -1 (-5000 2925)(-5000 1050);
WIRE 16 -1 (-4000 2925)(-5000 2925);
FORCEPROP 0 LAST SIG_NAME A_HSC_PSET
J 0
(-4635 2935);
DISPLAY 0.617021 (-4635 2935);
PAINT ORANGE (-4635 2935);
FORCEPROP 2 LASTPROP $XRERR UNIQUE?
J 0
(-4875 2935);
DISPLAY 0.638298 (-4875 2935);
PAINT MONO (-4875 2935);
DISPLAY INVISIBLE (-4875 2935);
WIRE 16 -1 (-5600 850)(-5600 975);
WIRE 16 -1 (-5600 975)(-5600 1400);
WIRE 16 -1 (-4925 975)(-5600 975);
WIRE 16 -1 (-4925 2875)(-4925 975);
WIRE 16 -1 (-4000 2875)(-4925 2875);
FORCEPROP 0 LAST SIG_NAME A_HSC_ISTART
J 0
(-4635 2885);
DISPLAY 0.617021 (-4635 2885);
PAINT ORANGE (-4635 2885);
FORCEPROP 2 LASTPROP $XRERR UNIQUE?
J 0
(-4875 2885);
DISPLAY 0.638298 (-4875 2885);
PAINT MONO (-4875 2885);
DISPLAY INVISIBLE (-4875 2885);
WIRE 16 -1 (-4850 2825)(-4850 1600);
WIRE 16 -1 (-4850 2825)(-5950 2825);
WIRE 16 -1 (-4000 2825)(-4850 2825);
FORCEPROP 0 LAST SIG_NAME A_HSC_TIMER
J 0
(-4635 2835);
DISPLAY 0.617021 (-4635 2835);
PAINT ORANGE (-4635 2835);
WIRE 16 -1 (-4625 2775)(-4625 1125);
WIRE 16 -1 (-4000 2775)(-4625 2775);
FORCEPROP 0 LAST SIG_NAME PD_HSC_RETRY_N
J 0
(-4635 2785);
DISPLAY 0.617021 (-4635 2785);
PAINT ORANGE (-4635 2785);
FORCEPROP 2 LASTPROP $XRERR UNIQUE?
J 0
(-4875 2785);
DISPLAY 0.638298 (-4875 2785);
PAINT MONO (-4875 2785);
DISPLAY INVISIBLE (-4875 2785);
WIRE 16 -1 (-5500 2675)(-4000 2675);
FORCEPROP 0 LAST SIG_NAME SMB_3V3SB_HSC_SDA_R
J 0
(-4610 2685);
DISPLAY 0.617021 (-4610 2685);
PAINT ORANGE (-4610 2685);
FORCEPROP 2 LASTPROP $XRERR UNIQUE?
J 0
(-4850 2685);
DISPLAY 0.638298 (-4850 2685);
PAINT MONO (-4850 2685);
DISPLAY INVISIBLE (-4850 2685);
WIRE 16 -1 (-4000 1875)(-4075 1875);
WIRE 16 -1 (-4075 1875)(-4075 1625);
WIRE 16 -1 (-4075 1625)(-2225 1625);
WIRE 16 -1 (-2225 1625)(-2225 2075);
WIRE 16 -1 (-2225 2075)(-825 2075);
FORCEPROP 0 LAST SIG_NAME A_HSC_MON
J 0
(-1435 2085);
DISPLAY 0.617021 (-1435 2085);
PAINT ORANGE (-1435 2085);
WIRE 3 682 (-7250 3450)(-6950 3450);
WIRE 3 682 (-7250 4200)(-7250 3450);
WIRE 3 682 (-6950 3450)(-6950 4200);
WIRE 3 682 (-6950 4200)(-7250 4200);
WIRE 16 -1 (-8000 2475)(-8000 2575);
WIRE 16 -1 (-8000 2850)(-8000 2575);
WIRE 16 -1 (-4000 2575)(-8000 2575);
FORCEPROP 0 LAST SIG_NAME FM_P12V_HSC_ADR1
J 0
(-4460 2585);
DISPLAY 0.617021 (-4460 2585);
PAINT ORANGE (-4460 2585);
FORCEPROP 2 LASTPROP $XRERR UNIQUE?
J 0
(-4700 2585);
DISPLAY 0.638298 (-4700 2585);
PAINT MONO (-4700 2585);
DISPLAY INVISIBLE (-4700 2585);
WIRE 16 -1 (-7675 2475)(-7675 2525);
WIRE 16 -1 (-7675 2525)(-7675 2850);
WIRE 16 -1 (-4000 2525)(-7675 2525);
FORCEPROP 0 LAST SIG_NAME FM_P12V_HSC_ADR2
J 0
(-4460 2535);
DISPLAY 0.617021 (-4460 2535);
PAINT ORANGE (-4460 2535);
FORCEPROP 2 LASTPROP $XRERR UNIQUE?
J 0
(-4700 2535);
DISPLAY 0.638298 (-4700 2535);
PAINT MONO (-4700 2535);
DISPLAY INVISIBLE (-4700 2535);
WIRE 3 682 (-6000 400)(-5700 400);
WIRE 3 682 (-6000 1200)(-6000 400);
WIRE 3 682 (-5700 400)(-5700 1200);
WIRE 3 682 (-5700 1200)(-6000 1200);
WIRE 16 -1 (-5875 975)(-5875 1100);
WIRE 16 -1 (-6150 950)(-6150 1100);
WIRE 16 -1 (-5875 1100)(-6150 1100);
WIRE 16 -1 (-6600 1075)(-6600 1100);
WIRE 16 -1 (-6600 1100)(-6150 1100);
WIRE 16 -1 (-6600 1100)(-6600 1150);
WIRE 16 -1 (-6600 1150)(-6600 1450);
WIRE 16 -1 (-5050 1150)(-6600 1150);
WIRE 16 -1 (-5050 2975)(-5050 1150);
WIRE 16 -1 (-4000 2975)(-5050 2975);
FORCEPROP 0 LAST SIG_NAME A_HSC_ISET
J 0
(-4610 2985);
DISPLAY 0.617021 (-4610 2985);
PAINT ORANGE (-4610 2985);
FORCEPROP 2 LASTPROP $XRERR UNIQUE?
J 0
(-4850 2985);
DISPLAY 0.638298 (-4850 2985);
PAINT MONO (-4850 2985);
DISPLAY INVISIBLE (-4850 2985);
WIRE 16 -1 (-4000 2425)(-4375 2425);
WIRE 16 -1 (-2825 925)(-2825 850);
WIRE 16 -1 (-2150 925)(-2825 925);
WIRE 16 -1 (-3125 975)(-3125 925);
WIRE 16 -1 (-2825 925)(-3125 925);
WIRE 16 -1 (-4375 2425)(-4375 925);
WIRE 16 -1 (-4375 925)(-3125 925);
FORCEPROP 0 LAST SIG_NAME PWRGD_P12V_R
J 0
(-3760 935);
DISPLAY 0.617021 (-3760 935);
PAINT ORANGE (-3760 935);
FORCEPROP 2 LASTPROP $XRERR UNIQUE?
J 0
(-4000 935);
DISPLAY 0.638298 (-4000 935);
PAINT MONO (-4000 935);
DISPLAY INVISIBLE (-4000 935);
WIRE 16 -1 (-1500 1850)(-1500 1800);
WIRE 16 -1 (-1500 1850)(-1350 1850);
WIRE 16 -1 (-4000 2175)(-4275 2175);
WIRE 16 -1 (-1825 1850)(-1500 1850);
WIRE 16 -1 (-1825 1425)(-1825 1850);
WIRE 16 -1 (-4275 2175)(-4275 1425);
WIRE 16 -1 (-4275 1425)(-1825 1425);
FORCEPROP 0 LAST SIG_NAME A_HSC_TEMP
J 0
(-3610 1435);
DISPLAY 0.617021 (-3610 1435);
PAINT ORANGE (-3610 1435);
FORCEPROP 2 LASTPROP $XRERR UNIQUE?
J 0
(-3850 1435);
DISPLAY 0.638298 (-3850 1435);
PAINT MONO (-3850 1435);
DISPLAY INVISIBLE (-3850 1435);
WIRE 16 -1 (-4000 2075)(-4225 2075);
WIRE 16 -1 (-4225 2075)(-4225 1475);
WIRE 16 -1 (-2075 1925)(-825 1925);
FORCEPROP 0 LAST SIG_NAME A_HSC_HSP
J 0
(-1435 1935);
DISPLAY 0.617021 (-1435 1935);
PAINT ORANGE (-1435 1935);
WIRE 16 -1 (-4225 1475)(-2075 1475);
WIRE 16 -1 (-2075 1475)(-2075 1925);
WIRE 16 -1 (-1950 1375)(-800 1375);
FORCEPROP 0 LAST SIG_NAME IRQ_HSC_FAULT_N
J 0
(-1285 1385);
DISPLAY 0.617021 (-1285 1385);
PAINT ORANGE (-1285 1385);
WIRE 3 682 (-5200 4050)(-5200 3700);
WIRE 3 682 (-4450 4050)(-5200 4050);
WIRE 3 682 (-5200 3700)(-4450 3700);
WIRE 3 682 (-4450 3700)(-4450 4050);
WIRE 16 -1 (-4000 2725)(-5500 2725);
FORCEPROP 0 LAST SIG_NAME SMB_3V3SB_HSC_SCL_R
J 0
(-4610 2735);
DISPLAY 0.617021 (-4610 2735);
PAINT ORANGE (-4610 2735);
FORCEPROP 2 LASTPROP $XRERR UNIQUE?
J 0
(-4850 2735);
DISPLAY 0.638298 (-4850 2735);
PAINT MONO (-4850 2735);
DISPLAY INVISIBLE (-4850 2735);
WIRE 16 -1 (-7025 2325)(-7025 2275);
WIRE 16 -1 (-7025 2325)(-6725 2325);
WIRE 16 -1 (-4000 2325)(-6725 2325);
WIRE 16 -1 (-6725 2450)(-6725 2325);
WIRE 16 -1 (-7175 2450)(-6725 2450);
FORCEPROP 0 LAST SIG_NAME FM_P12V_HOTSWAP0_EN
J 0
(-7160 2460);
DISPLAY 0.617021 (-7160 2460);
PAINT ORANGE (-7160 2460);
WIRE 16 -1 (-6725 1875)(-6725 1825);
WIRE 16 -1 (-6725 1925)(-6725 1875);
WIRE 16 -1 (-4000 2225)(-5925 2225);
WIRE 16 -1 (-5925 1875)(-6725 1875);
FORCEPROP 0 LAST SIG_NAME A_HSC_PWGIN
J 0
(-6335 1885);
DISPLAY 0.617021 (-6335 1885);
PAINT ORANGE (-6335 1885);
FORCEPROP 2 LASTPROP $XRERR UNIQUE?
J 0
(-6575 1885);
DISPLAY 0.638298 (-6575 1885);
PAINT MONO (-6575 1885);
DISPLAY INVISIBLE (-6575 1885);
WIRE 16 -1 (-5925 1875)(-5925 2225);
WIRE 16 -1 (-4325 1375)(-2150 1375);
FORCEPROP 0 LAST SIG_NAME IRQ_HSC_FAULT_R_N
J 0
(-2785 1385);
DISPLAY 0.617021 (-2785 1385);
PAINT ORANGE (-2785 1385);
FORCEPROP 2 LASTPROP $XRERR UNIQUE?
J 0
(-3025 1385);
DISPLAY 0.638298 (-3025 1385);
PAINT MONO (-3025 1385);
DISPLAY INVISIBLE (-3025 1385);
WIRE 16 -1 (-4325 2375)(-4325 1375);
WIRE 16 -1 (-4325 2375)(-4000 2375);
WIRE 3 682 (-6750 500)(-6400 500);
WIRE 3 682 (-6750 1200)(-6750 500);
WIRE 3 682 (-6400 500)(-6400 1200);
WIRE 3 682 (-6400 1200)(-6750 1200);
WIRE 16 -1 (-6600 600)(-6600 875);
FORCEPROP 0 LAST SIG_NAME A_HSC_ISET_S
R 1
J 0
(-6610 560);
DISPLAY 0.617021 (-6610 560);
PAINT ORANGE (-6610 560);
FORCEPROP 2 LASTPROP $XRERR UNIQUE?
J 0
(-6850 560);
DISPLAY 0.638298 (-6850 560);
PAINT MONO (-6850 560);
DISPLAY INVISIBLE (-6850 560);
WIRE 16 -1 (-5875 775)(-5875 475);
FORCEPROP 0 LAST SIG_NAME A_HSC_ISET_S2
R 1
J 0
(-5885 460);
DISPLAY 0.617021 (-5885 460);
PAINT ORANGE (-5885 460);
FORCEPROP 2 LASTPROP $XRERR UNIQUE?
J 0
(-6125 460);
DISPLAY 0.638298 (-6125 460);
PAINT MONO (-6125 460);
DISPLAY INVISIBLE (-6125 460);
WIRE 16 -1 (-7625 1225)(-7375 1225);
WIRE 16 -1 (-7375 1375)(-7375 1225);
WIRE 16 -1 (-7375 1225)(-7125 1225);
WIRE 16 -1 (-7125 1225)(-6825 1225);
WIRE 16 -1 (-7125 1375)(-7375 1375);
WIRE 16 -1 (-7125 1375)(-7125 1225);
WIRE 16 -1 (-8000 1225)(-7625 1225);
WIRE 16 -1 (-7625 1375)(-7625 1225);
WIRE 16 -1 (-7375 1375)(-7625 1375);
WIRE 16 -1 (-7625 1375)(-8000 1375);
WIRE 16 -1 (-8000 1225)(-8000 1275);
WIRE 16 -1 (-6825 1375)(-7125 1375);
WIRE 16 -1 (-6825 1275)(-6825 1225);
WIRE 16 -1 (-8000 1275)(-6825 1275);
WIRE 16 -1 (-6825 1325)(-6825 1275);
WIRE 16 -1 (-6825 1375)(-6825 1325);
WIRE 16 -1 (-8000 1325)(-8000 1275);
WIRE 16 -1 (-8000 1375)(-8000 1325);
WIRE 16 -1 (-8000 1325)(-6825 1325);
WIRE 16 -1 (-8000 1050)(-7625 1050);
WIRE 16 -1 (-7625 1200)(-7625 1050);
WIRE 16 -1 (-7625 1050)(-7375 1050);
WIRE 16 -1 (-7375 1050)(-7125 1050);
WIRE 16 -1 (-7375 1200)(-7625 1200);
WIRE 16 -1 (-7375 1200)(-7375 1050);
WIRE 16 -1 (-7625 1200)(-8000 1200);
WIRE 16 -1 (-7125 1050)(-6825 1050);
WIRE 16 -1 (-8000 1100)(-8000 1050);
WIRE 16 -1 (-8000 1100)(-6825 1100);
WIRE 16 -1 (-6825 1050)(-6825 1100);
WIRE 16 -1 (-8000 1150)(-8000 1100);
WIRE 16 -1 (-8000 1200)(-8000 1150);
WIRE 16 -1 (-7125 1200)(-7375 1200);
WIRE 16 -1 (-7125 1200)(-7125 1050);
WIRE 16 -1 (-6825 1200)(-7125 1200);
WIRE 16 -1 (-8000 1150)(-6825 1150);
WIRE 16 -1 (-6825 1100)(-6825 1150);
WIRE 16 -1 (-6825 1150)(-6825 1200);
WIRE 3 2175 (-7850 925)(-7600 925);
WIRE 3 2175 (-7600 925)(-7600 50);
WIRE 3 2175 (-7850 925)(-7850 50);
WIRE 3 2175 (-7850 50)(-7600 50);
WIRE 16 -1 (-7550 700)(-7450 700);
WIRE 16 -1 (-7450 700)(-7450 250);
WIRE 16 -1 (-7300 250)(-7450 250);
WIRE 16 -1 (-7300 250)(-7300 650);
FORCEPROP 0 LAST SIG_NAME A_HSC_OCP_SEL
R 1
J 0
(-7302 327);
DISPLAY 0.617021 (-7302 327);
PAINT ORANGE (-7302 327);
FORCEPROP 2 LASTPROP $XRERR UNIQUE?
J 0
(-7542 327);
DISPLAY 0.638298 (-7542 327);
PAINT MONO (-7542 327);
DISPLAY INVISIBLE (-7542 327);
WIRE 16 -1 (-7950 650)(-7950 175);
WIRE 16 -1 (-6300 175)(-7950 175);
FORCEPROP 0 LAST SIG_NAME A_HSC_LOW_EN
J 0
(-7302 177);
DISPLAY 0.617021 (-7302 177);
PAINT ORANGE (-7302 177);
FORCEPROP 2 LASTPROP $XRERR UNIQUE?
J 0
(-7542 177);
DISPLAY 0.638298 (-7542 177);
PAINT MONO (-7542 177);
DISPLAY INVISIBLE (-7542 177);
WIRE 16 -1 (-6300 50)(-6300 175);
WIRE 16 -1 (-6075 175)(-6300 175);
WIRE 68 -1 (-1750 1450)(-1750 1900);
WIRE 68 -1 (-1050 1450)(-1750 1450);
WIRE 68 -1 (-1050 1900)(-1750 1900);
WIRE 68 -1 (-1050 1900)(-1050 1450);
WIRE 16 -1 (-7950 800)(-8050 800);
WIRE 16 -1 (-8050 800)(-8050 300);
WIRE 16 -1 (-6950 300)(-8050 300);
WIRE 16 -1 (-6950 300)(-6950 50);
WIRE 16 -1 (-6800 300)(-6950 300);
FORCEPROP 0 LAST SIG_NAME A_HSC_HIGH_EN
J 0
(-7277 302);
DISPLAY 0.617021 (-7277 302);
PAINT ORANGE (-7277 302);
FORCEPROP 2 LASTPROP $XR0 199 
J 0
(-7547 302);
DISPLAY 0.638298 (-7547 302);
PAINT MONO (-7547 302);
DISPLAY INVISIBLE (-7547 302);
WIRE 16 -1 (-4000 2275)(-4575 2275);
FORCEPROP 0 LAST SIG_NAME TP_HSC_SPISSN
J 0
(-4560 2285);
DISPLAY 0.617021 (-4560 2285);
PAINT ORANGE (-4560 2285);
FORCEPROP 2 LASTPROP $XRERR UNIQUE?
J 0
(-4815 2275);
DISPLAY 0.638298 (-4815 2275);
PAINT MONO (-4815 2275);
DISPLAY INVISIBLE (-4815 2275);
WIRE 16 -1 (-4000 1925)(-4125 1925);
WIRE 16 -1 (-4125 1925)(-4125 1575);
WIRE 16 -1 (-2175 2025)(-825 2025);
FORCEPROP 0 LAST SIG_NAME A_HSC_MOP
J 0
(-1435 2035);
DISPLAY 0.617021 (-1435 2035);
PAINT ORANGE (-1435 2035);
WIRE 16 -1 (-4125 1575)(-2175 1575);
WIRE 16 -1 (-2175 1575)(-2175 2025);
WIRE 16 -1 (-4000 2025)(-4175 2025);
WIRE 16 -1 (-4175 2025)(-4175 1525);
WIRE 16 -1 (-2125 1975)(-825 1975);
FORCEPROP 0 LAST SIG_NAME A_HSC_HSN
J 0
(-1435 1985);
DISPLAY 0.617021 (-1435 1985);
PAINT ORANGE (-1435 1985);
WIRE 16 -1 (-4175 1525)(-2125 1525);
WIRE 16 -1 (-2125 1525)(-2125 1975);
WIRE 16 -1 (-5700 2675)(-6700 2675);
FORCEPROP 0 LAST SIG_NAME SMB_BMC_PMBUS_STBY_LVC3_SDA
J 0
(-6660 2685);
DISPLAY 0.617021 (-6660 2685);
PAINT ORANGE (-6660 2685);
WIRE 16 -1 (-5700 2725)(-6700 2725);
FORCEPROP 0 LAST SIG_NAME SMB_BMC_PMBUS_STBY_LVC3_SCL
J 0
(-6660 2735);
DISPLAY 0.617021 (-6660 2735);
PAINT ORANGE (-6660 2735);
WIRE 16 -1 (-2500 2725)(-875 2725);
FORCEPROP 0 LAST SIG_NAME A_HSC_GATE
J 0
(-1335 2735);
DISPLAY 0.617021 (-1335 2735);
PAINT ORANGE (-1335 2735);
WIRE 16 -1 (-2500 3025)(-1975 3025);
FORCEPROP 0 LAST SIG_NAME TP_HSC_MDAT
J 0
(-2410 3035);
DISPLAY 0.617021 (-2410 3035);
PAINT ORANGE (-2410 3035);
FORCEPROP 2 LASTPROP $XRERR UNIQUE?
J 0
(-1945 3025);
DISPLAY 0.638298 (-1945 3025);
PAINT MONO (-1945 3025);
DISPLAY INVISIBLE (-1945 3025);
WIRE 16 -1 (-2500 3125)(-1975 3125);
FORCEPROP 0 LAST SIG_NAME TP_HSC_MCLK
J 0
(-2410 3135);
DISPLAY 0.617021 (-2410 3135);
PAINT ORANGE (-2410 3135);
FORCEPROP 2 LASTPROP $XRERR UNIQUE?
J 0
(-1945 3125);
DISPLAY 0.638298 (-1945 3125);
PAINT MONO (-1945 3125);
DISPLAY INVISIBLE (-1945 3125);
WIRE 16 -1 (-875 3950)(-1600 3950);
FORCEPROP 0 LAST SIG_NAME IRQ_SML1_PMBUS_ALERT_N
J 0
(-1535 3960);
DISPLAY 0.617021 (-1535 3960);
PAINT ORANGE (-1535 3960);
WIRE 16 -1 (-4100 100)(-3550 100);
FORCEPROP 0 LAST SIG_NAME A_HSC_HIGH_EN
J 0
(-4027 102);
DISPLAY 0.617021 (-4027 102);
PAINT ORANGE (-4027 102);
FORCEPROP 2 LASTPROP $XR0 199 
J 0
(-4256 100);
DISPLAY 0.638298 (-4256 100);
PAINT MONO (-4256 100);
WIRE 16 -1 (-475 1600)(-475 1550);
WIRE 16 -1 (-1150 1550)(-475 1550);
FORCEPROP 2 LAST SIG_NAME TEMP_SENSOR_E
J 0
(-1035 1560);
DISPLAY 0.638298 (-1035 1560);
PAINT ORANGE (-1035 1560);
FORCEPROP 2 LASTPROP $XRERR UNIQUE?
J 0
(-1275 1560);
DISPLAY 0.638298 (-1275 1560);
PAINT MONO (-1275 1560);
DISPLAY INVISIBLE (-1275 1560);
WIRE 16 -1 (-475 1800)(-475 1850);
WIRE 16 -1 (-700 1700)(-625 1700);
WIRE 16 -1 (-700 1850)(-700 1700);
WIRE 16 -1 (-475 1850)(-700 1850);
WIRE 16 -1 (-1150 1850)(-700 1850);
FORCEPROP 2 LAST SIG_NAME TEMP_SENSOR_B
J 0
(-1035 1860);
DISPLAY 0.638298 (-1035 1860);
PAINT ORANGE (-1035 1860);
FORCEPROP 2 LASTPROP $XRERR UNIQUE?
J 0
(-1275 1860);
DISPLAY 0.638298 (-1275 1860);
PAINT MONO (-1275 1860);
DISPLAY INVISIBLE (-1275 1860);
WIRE 16 -1 (-800 925)(-1950 925);
FORCEPROP 0 LAST SIG_NAME PWRGD_P12V_HSC
J 0
(-1685 935);
DISPLAY 0.617021 (-1685 935);
PAINT ORANGE (-1685 935);
WIRE 16 -1 (-3350 450)(-2750 450);
FORCEPROP 0 LAST SIG_NAME A_HSC_LOW_GATE
J 0
(-3247 472);
DISPLAY 0.617021 (-3247 472);
PAINT ORANGE (-3247 472);
WIRE 16 -1 (-3350 400)(-3350 450);
WIRE 3 2175 (-4150 -100)(-2275 -100);
WIRE 3 2175 (-2275 525)(-2275 -100);
WIRE 3 2175 (-4150 525)(-4150 -100);
WIRE 3 2175 (-4150 525)(-2275 525);
WIRE 16 -1 (-400 2825)(-400 2725);
WIRE 16 -1 (-400 2825)(-400 2925);
WIRE 16 -1 (-2500 2825)(-400 2825);
FORCEPROP 0 LAST SIG_NAME A_HSC_VOUT
J 0
(-1335 2835);
DISPLAY 0.617021 (-1335 2835);
PAINT ORANGE (-1335 2835);
FORCEPROP 2 LASTPROP $XRERR UNIQUE?
J 0
(-1575 2835);
DISPLAY 0.638298 (-1575 2835);
PAINT MONO (-1575 2835);
DISPLAY INVISIBLE (-1575 2835);
WIRE 16 -1 (-2500 2925)(-875 2925);
FORCEPROP 0 LAST SIG_NAME A_HSC_CSOUT
J 0
(-1335 2935);
DISPLAY 0.617021 (-1335 2935);
PAINT ORANGE (-1335 2935);
WIRE 16 -1 (-875 3275)(-2500 3275);
FORCEPROP 0 LAST SIG_NAME IRQ_SML1_PMBUS_ALERT_R_N
J 0
(-2410 3285);
DISPLAY 0.617021 (-2410 3285);
PAINT ORANGE (-2410 3285);
WIRE 16 -1 (-2500 3225)(-1975 3225);
FORCEPROP 0 LAST SIG_NAME TP_HSC_ALERT2_N
J 0
(-2410 3235);
DISPLAY 0.617021 (-2410 3235);
PAINT ORANGE (-2410 3235);
FORCEPROP 2 LASTPROP $XRERR UNIQUE?
J 0
(-1945 3225);
DISPLAY 0.638298 (-1945 3225);
PAINT MONO (-1945 3225);
DISPLAY INVISIBLE (-1945 3225);
WIRE 16 -1 (-1800 3950)(-2575 3950);
FORCEPROP 0 LAST SIG_NAME IRQ_SML1_PMBUS_ALERT_R_N
J 0
(-2510 3960);
DISPLAY 0.617021 (-2510 3960);
PAINT ORANGE (-2510 3960);
DOT 1 (-6600 1150);
DOT 1 (-6825 1100);
DOT 1 (-6600 1100);
DOT 1 (-6825 1150);
DOT 1 (-6825 1275);
DOT 1 (-6825 1325);
DOT 1 (-6150 1100);
DOT 1 (-5000 1050);
DOT 1 (-5400 575);
DOT 1 (-6300 175);
DOT 1 (-7375 1050);
DOT 1 (-8000 1325);
DOT 1 (-8000 1275);
DOT 1 (-7125 1050);
DOT 1 (-7125 1225);
DOT 1 (-7375 1225);
DOT 1 (-7375 1200);
DOT 1 (-7125 1375);
DOT 1 (-7825 3125);
DOT 1 (-7125 1200);
DOT 1 (-7625 1050);
DOT 1 (-8000 1100);
DOT 1 (-8000 1150);
DOT 1 (-7625 1200);
DOT 1 (-7375 1375);
DOT 1 (-7625 1375);
DOT 1 (-7625 1225);
DOT 1 (-6675 4225);
DOT 1 (-6500 4225);
DOT 1 (-6775 3800);
DOT 1 (-6500 3800);
DOT 1 (-5100 3175);
DOT 1 (-7675 2525);
DOT 1 (-8000 2575);
DOT 1 (-6300 -225);
DOT 1 (-3125 925);
DOT 1 (-1500 1550);
DOT 1 (-400 2825);
DOT 1 (-5525 4225);
DOT 1 (-5100 2150);
DOT 1 (-6075 3800);
DOT 1 (-4725 750);
DOT 1 (-5300 1700);
DOT 1 (-5600 1700);
DOT 1 (-5300 1050);
DOT 1 (-6375 3350);
DOT 1 (-6725 2325);
DOT 1 (-7200 3800);
DOT 1 (-7200 3325);
DOT 1 (-6725 1875);
DOT 1 (-2825 925);
DOT 1 (-6950 300);
DOT 1 (-1500 1850);
DOT 1 (-700 1850);
DOT 1 (-5600 975);
DOT 1 (-4850 2825);
DOT 1 (-7675 2150);
DOT 1 (-5525 3825);
FORCENOTE
PSET: 78W
(-6050 1575) 0;
DISPLAY LEFT (-6050 1575);
DISPLAY 1.021277 (-6050 1575);
PAINT PURPLE (-6050 1575);
FORCENOTE
TP FAB1 CHANGE RES 0429
(-6000 1250) 0;
DISPLAY LEFT (-6000 1250);
DISPLAY 0.638298 (-6000 1250);
PAINT RED (-6000 1250);
FORCENOTE
TP FAB3 CHANGE RES FOR DOUBLE SIDE 1006
(-6000 1200) 0;
DISPLAY LEFT (-6000 1200);
DISPLAY 0.638298 (-6000 1200);
PAINT RED (-6000 1200);
FORCENOTE
DEFAULT
(-7100 1050) 0;
DISPLAY LEFT (-7100 1050);
DISPLAY 0.808511 (-7100 1050);
PAINT PURPLE (-7100 1050);
FORCENOTE
ISTART: 9.92A
(-5525 1725) 0;
DISPLAY LEFT (-5525 1725);
DISPLAY 1.021277 (-5525 1725);
PAINT PURPLE (-5525 1725);
FORCENOTE
DEFAULT
(-7100 1275) 0;
DISPLAY LEFT (-7100 1275);
DISPLAY 0.808511 (-7100 1275);
PAINT PURPLE (-7100 1275);
FORCENOTE
47.9A
(-7350 1275) 0;
DISPLAY LEFT (-7350 1275);
DISPLAY 0.808511 (-7350 1275);
PAINT PURPLE (-7350 1275);
FORCENOTE
40.6A
(-7350 1225) 0;
DISPLAY LEFT (-7350 1225);
DISPLAY 0.808511 (-7350 1225);
PAINT PURPLE (-7350 1225);
FORCENOTE
77.3A
(-7350 1100) 0;
DISPLAY LEFT (-7350 1100);
DISPLAY 0.808511 (-7350 1100);
PAINT PURPLE (-7350 1100);
FORCENOTE
70A
(-7350 1050) 0;
DISPLAY LEFT (-7350 1050);
DISPLAY 0.808511 (-7350 1050);
PAINT PURPLE (-7350 1050);
FORCENOTE
DOUBLE SIDE
(-7975 1150) 0;
DISPLAY LEFT (-7975 1150);
DISPLAY 0.808511 (-7975 1150);
PAINT PURPLE (-7975 1150);
FORCENOTE
71.5A
(-7600 1050) 0;
DISPLAY LEFT (-7600 1050);
DISPLAY 0.808511 (-7600 1050);
PAINT PURPLE (-7600 1050);
FORCENOTE
41.4A
(-7600 1225) 0;
DISPLAY LEFT (-7600 1225);
DISPLAY 0.808511 (-7600 1225);
PAINT PURPLE (-7600 1225);
FORCENOTE
SINGLE SIDE
(-7975 1325) 0;
DISPLAY LEFT (-7975 1325);
DISPLAY 0.808511 (-7975 1325);
PAINT PURPLE (-7975 1325);
FORCENOTE
PIN 1-2
(-7975 1275) 0;
DISPLAY LEFT (-7975 1275);
DISPLAY 0.808511 (-7975 1275);
PAINT PURPLE (-7975 1275);
FORCENOTE
PIN 1-2
(-7975 1100) 0;
DISPLAY LEFT (-7975 1100);
DISPLAY 0.808511 (-7975 1100);
PAINT PURPLE (-7975 1100);
FORCENOTE
PIN 2-3
(-7975 1050) 0;
DISPLAY LEFT (-7975 1050);
DISPLAY 0.808511 (-7975 1050);
PAINT PURPLE (-7975 1050);
FORCENOTE
78.9A
(-7600 1100) 0;
DISPLAY LEFT (-7600 1100);
DISPLAY 0.808511 (-7600 1100);
PAINT PURPLE (-7600 1100);
FORCENOTE
FPH
(-7350 1150) 0;
DISPLAY LEFT (-7350 1150);
DISPLAY 0.808511 (-7350 1150);
PAINT PURPLE (-7350 1150);
FORCENOTE
OCP
(-7600 1150) 0;
DISPLAY LEFT (-7600 1150);
DISPLAY 0.808511 (-7600 1150);
PAINT PURPLE (-7600 1150);
FORCENOTE
48.8A 
(-7600 1275) 0;
DISPLAY LEFT (-7600 1275);
DISPLAY 0.808511 (-7600 1275);
PAINT PURPLE (-7600 1275);
FORCENOTE
FPH
(-7350 1325) 0;
DISPLAY LEFT (-7350 1325);
DISPLAY 0.808511 (-7350 1325);
PAINT PURPLE (-7350 1325);
FORCENOTE
OCP
(-7600 1325) 0;
DISPLAY LEFT (-7600 1325);
DISPLAY 0.808511 (-7600 1325);
PAINT PURPLE (-7600 1325);
FORCENOTE
TP FAB3 NOPOP R1D29 AND POP R9P17 ON BOTH SS AND DS 0901
(-7400 2900) 0;
DISPLAY LEFT (-7400 2900);
DISPLAY 0.638298 (-7400 2900);
PAINT RED (-7400 2900);
FORCENOTE
TP FAB3 NOPOP R9P16 ON DS BOM 0901
(-7400 2850) 0;
DISPLAY LEFT (-7400 2850);
DISPLAY 0.638298 (-7400 2850);
PAINT RED (-7400 2850);
FORCENOTE
THRESHOLD 9.26V
(-6675 2200) 0;
DISPLAY LEFT (-6675 2200);
DISPLAY 1.021277 (-6675 2200);
PAINT PURPLE (-6675 2200);
FORCENOTE
DS: 0X45 (7 BIT), 0X8A (8BIT)
(-8000 1800) 0;
DISPLAY LEFT (-8000 1800);
DISPLAY 1.021277 (-8000 1800);
PAINT PURPLE (-8000 1800);
FORCENOTE
PIN 2-3 
(-7975 1225) 0;
DISPLAY LEFT (-7975 1225);
DISPLAY 0.808511 (-7975 1225);
PAINT PURPLE (-7975 1225);
FORCENOTE
TIMER: 620US
(-4900 1650) 0;
DISPLAY LEFT (-4900 1650);
DISPLAY 1.021277 (-4900 1650);
PAINT PURPLE (-4900 1650);
FORCENOTE
TP FAB1 ADD MOS 1231
(-2200 -75) 0;
DISPLAY LEFT (-2200 -75);
DISPLAY 1.021277 (-2200 -75);
PAINT RED (-2200 -75);
FORCENOTE
ROOM: HOT_SWAP
(-7925 -225) 0;
DISPLAY LEFT (-7925 -225);
DISPLAY 1.595745 (-7925 -225);
PAINT PURPLE (-7925 -225);
FORCENOTE
TP FAB1  ADD J1B4 AND DELETE J1B3 0113
(-8025 -25) 0;
DISPLAY LEFT (-8025 -25);
DISPLAY 0.808511 (-8025 -25);
PAINT RED (-8025 -25);
FORCENOTE
PMBUS ADDRESS :
(-8000 1950) 0;
DISPLAY LEFT (-8000 1950);
DISPLAY 1.021277 (-8000 1950);
PAINT PURPLE (-8000 1950);
FORCENOTE
TP FAB3 NOPOP R1D29 ON SINGLE SIDE MB AND POP IT ON DOUBLE SIDE MB 0803
(-7400 3000) 0;
DISPLAY LEFT (-7400 3000);
DISPLAY 0.638298 (-7400 3000);
PAINT RED (-7400 3000);
FORCENOTE
TP FAB3 POP R9P17 ON SINGLE SIDE MB AND NOPOP IT ON DOUBLE SIDE MB 0803
(-7400 2950) 0;
DISPLAY LEFT (-7400 2950);
DISPLAY 0.638298 (-7400 2950);
PAINT RED (-7400 2950);
FORCENOTE
TP FAB3-DVT CHANGE ZENER DIODE'S REVERSE STAND-OFF VOLTAGE TO 14V.
(-5075 3650) 0;
DISPLAY LEFT (-5075 3650);
DISPLAY 0.638298 (-5075 3650);
PAINT RED (-5075 3650);
FORCENOTE
EMPTY = LATCH-OFF MODE (DEFAULT)
(-4625 600) 0;
DISPLAY LEFT (-4625 600);
DISPLAY 1.021277 (-4625 600);
PAINT PURPLE (-4625 600);
FORCENOTE
STUFF = RETRY MODE
(-4625 550) 0;
DISPLAY LEFT (-4625 550);
DISPLAY 1.021277 (-4625 550);
PAINT PURPLE (-4625 550);
FORCENOTE
TP FAB3 CHANGE RES FOR DOUBLE SIDE 1006
(-6750 1300) 0;
DISPLAY LEFT (-6750 1300);
DISPLAY 0.638298 (-6750 1300);
PAINT RED (-6750 1300);
FORCENOTE
SS: 0X11 (7 BIT), 0X22 (8BIT)
(-8000 1875) 0;
DISPLAY LEFT (-8000 1875);
DISPLAY 1.021277 (-8000 1875);
PAINT PURPLE (-8000 1875);
FORCENOTE
TP FAB4 CHANGE R9P28 TO 100K 20170505
(-7550 4275) 0;
DISPLAY LEFT (-7550 4275);
DISPLAY 0.638298 (-7550 4275);
PAINT RED (-7550 4275);
FORCENOTE
TP FAB1 CHANGE RES 0422
(-7550 4325) 0;
DISPLAY LEFT (-7550 4325);
DISPLAY 0.638298 (-7550 4325);
PAINT RED (-7550 4325);
FORCENOTE
TP FAB1 ADD C1W16, R1W20 AND R1W21 0115
(-1975 1150) 0;
DISPLAY LEFT (-1975 1150);
DISPLAY 1.021277 (-1975 1150);
PAINT RED (-1975 1150);
FORCENOTE
LAYOUT NOTE: CLOSE TO Q1D3
(-1600 1275) 0;
DISPLAY LEFT (-1600 1275);
DISPLAY 1.021277 (-1600 1275);
PAINT PURPLE (-1600 1275);
FORCENOTE
UV: P12V_PSU <= 10.091V (9.812V~10.377V)
(-6550 4250) 0;
DISPLAY LEFT (-6550 4250);
DISPLAY 1.021277 (-6550 4250);
PAINT PURPLE (-6550 4250);
FORCENOTE
OV: P12V_PSU >= 14.33V (13.929V~14.749V)
(-6550 4325) 0;
DISPLAY LEFT (-6550 4325);
DISPLAY 1.021277 (-6550 4325);
PAINT PURPLE (-6550 4325);
QUIT
